FILE_TYPE = MACRO_DRAWING;
SET COLOR_WIRE YELLOW;
SET COLOR_PROP ORANGE;
SET COLOR_DOT WHITE;
SET COLOR_ARC YELLOW;
SET COLOR_BODY GREEN;
SET COLOR_NOTE PURPLE;
SET PROP_DISPLAY VALUE;
SET PAGE_NUMBER P18;
FORCEADD GENOA_SP5..9
(-4525 3600);
FORCEPROP 1 LAST LOCATION U25
J 0
(-5170 6431);
DISPLAY 0.489362 (-5170 6431);
PAINT SKYBLUE (-5170 6431);
FORCEPROP 0 LAST $SEC 9
J 0
(-5150 6475);
DISPLAY 0.680851 (-5150 6475);
PAINT MONO (-5150 6475);
DISPLAY INVISIBLE (-5150 6475);
FORCEPROP 0 LAST CDS_SEC 9
J 0
(-5175 6400);
DISPLAY 1.021277 (-5175 6400);
DISPLAY INVISIBLE (-5175 6400);
FORCEPROP 0 LASTPIN (-5325 2975) $PN BC19
J 2
(-5335 2985);
DISPLAY 0.489362 (-5335 2985);
PAINT MONO (-5335 2985);
FORCEPROP 0 LASTPIN (-5325 2925) $PN BD20
J 2
(-5335 2935);
DISPLAY 0.489362 (-5335 2935);
PAINT MONO (-5335 2935);
FORCEPROP 0 LASTPIN (-5325 1825) $PN BF20
J 2
(-5335 1835);
DISPLAY 0.489362 (-5335 1835);
PAINT MONO (-5335 1835);
FORCEPROP 0 LASTPIN (-5325 1775) $PN BG19
J 2
(-5335 1785);
DISPLAY 0.489362 (-5335 1785);
PAINT MONO (-5335 1785);
FORCEPROP 0 LASTPIN (-5325 2125) $PN AT21
J 2
(-5335 2135);
DISPLAY 0.489362 (-5335 2135);
PAINT MONO (-5335 2135);
FORCEPROP 0 LASTPIN (-5325 2025) $PN AU21
J 2
(-5335 2035);
DISPLAY 0.489362 (-5335 2035);
PAINT MONO (-5335 2035);
FORCEPROP 0 LASTPIN (-5325 2825) $PN AU19
J 2
(-5335 2835);
DISPLAY 0.489362 (-5335 2835);
PAINT MONO (-5335 2835);
FORCEPROP 0 LASTPIN (-5325 2775) $PN AV21
J 2
(-5335 2785);
DISPLAY 0.489362 (-5335 2785);
PAINT MONO (-5335 2785);
FORCEPROP 0 LASTPIN (-5325 2675) $PN BN21
J 2
(-5335 2685);
DISPLAY 0.489362 (-5335 2685);
PAINT MONO (-5335 2685);
FORCEPROP 0 LASTPIN (-5325 1675) $PN AV20
J 2
(-5335 1685);
DISPLAY 0.489362 (-5335 1685);
PAINT MONO (-5335 1685);
FORCEPROP 0 LASTPIN (-5325 1625) $PN AW21
J 2
(-5335 1635);
DISPLAY 0.489362 (-5335 1635);
PAINT MONO (-5335 1635);
FORCEPROP 0 LASTPIN (-5325 1525) $PN BP21
J 2
(-5335 1535);
DISPLAY 0.489362 (-5335 1535);
PAINT MONO (-5335 1535);
FORCEPROP 0 LASTPIN (-5325 3825) $PN AW19
J 2
(-5335 3835);
DISPLAY 0.489362 (-5335 3835);
PAINT MONO (-5335 3835);
FORCEPROP 0 LASTPIN (-5325 3775) $PN AY20
J 2
(-5335 3785);
DISPLAY 0.489362 (-5335 3785);
PAINT MONO (-5335 3785);
FORCEPROP 0 LASTPIN (-5325 3725) $PN AY21
J 2
(-5335 3735);
DISPLAY 0.489362 (-5335 3735);
PAINT MONO (-5335 3735);
FORCEPROP 0 LASTPIN (-5325 3675) $PN BA21
J 2
(-5335 3685);
DISPLAY 0.489362 (-5335 3685);
PAINT MONO (-5335 3685);
FORCEPROP 0 LASTPIN (-5325 3625) $PN BA19
J 2
(-5335 3635);
DISPLAY 0.489362 (-5335 3635);
PAINT MONO (-5335 3635);
FORCEPROP 0 LASTPIN (-5325 3575) $PN BB20
J 2
(-5335 3585);
DISPLAY 0.489362 (-5335 3585);
PAINT MONO (-5335 3585);
FORCEPROP 0 LASTPIN (-5325 3525) $PN BB21
J 2
(-5335 3535);
DISPLAY 0.489362 (-5335 3535);
PAINT MONO (-5335 3535);
FORCEPROP 0 LASTPIN (-3725 2375) $PN AJ19
J 0
(-3715 2385);
DISPLAY 0.489362 (-3715 2385);
PAINT MONO (-3715 2385);
FORCEPROP 0 LASTPIN (-3725 2325) $PN AK21
J 0
(-3715 2335);
DISPLAY 0.489362 (-3715 2335);
PAINT MONO (-3715 2335);
FORCEPROP 0 LASTPIN (-3725 2275) $PN AK20
J 0
(-3715 2285);
DISPLAY 0.489362 (-3715 2285);
PAINT MONO (-3715 2285);
FORCEPROP 0 LASTPIN (-3725 2225) $PN AL21
J 0
(-3715 2235);
DISPLAY 0.489362 (-3715 2235);
PAINT MONO (-3715 2235);
FORCEPROP 0 LASTPIN (-3725 2175) $PN AN19
J 0
(-3715 2185);
DISPLAY 0.489362 (-3715 2185);
PAINT MONO (-3715 2185);
FORCEPROP 0 LASTPIN (-3725 2125) $PN AP21
J 0
(-3715 2135);
DISPLAY 0.489362 (-3715 2135);
PAINT MONO (-3715 2135);
FORCEPROP 0 LASTPIN (-3725 2075) $PN AP20
J 0
(-3715 2085);
DISPLAY 0.489362 (-3715 2085);
PAINT MONO (-3715 2085);
FORCEPROP 0 LASTPIN (-3725 2025) $PN AR21
J 0
(-3715 2035);
DISPLAY 0.489362 (-3715 2035);
PAINT MONO (-3715 2035);
FORCEPROP 0 LASTPIN (-3725 5975) $PN E19
J 0
(-3715 5985);
DISPLAY 0.489362 (-3715 5985);
PAINT MONO (-3715 5985);
FORCEPROP 0 LASTPIN (-3725 5925) $PN F21
J 0
(-3715 5935);
DISPLAY 0.489362 (-3715 5935);
PAINT MONO (-3715 5935);
FORCEPROP 0 LASTPIN (-3725 5875) $PN F20
J 0
(-3715 5885);
DISPLAY 0.489362 (-3715 5885);
PAINT MONO (-3715 5885);
FORCEPROP 0 LASTPIN (-3725 5825) $PN G21
J 0
(-3715 5835);
DISPLAY 0.489362 (-3715 5835);
PAINT MONO (-3715 5835);
FORCEPROP 0 LASTPIN (-3725 5775) $PN J19
J 0
(-3715 5785);
DISPLAY 0.489362 (-3715 5785);
PAINT MONO (-3715 5785);
FORCEPROP 0 LASTPIN (-3725 5725) $PN K21
J 0
(-3715 5735);
DISPLAY 0.489362 (-3715 5735);
PAINT MONO (-3715 5735);
FORCEPROP 0 LASTPIN (-3725 5675) $PN K20
J 0
(-3715 5685);
DISPLAY 0.489362 (-3715 5685);
PAINT MONO (-3715 5685);
FORCEPROP 0 LASTPIN (-3725 5625) $PN L21
J 0
(-3715 5635);
DISPLAY 0.489362 (-3715 5635);
PAINT MONO (-3715 5635);
FORCEPROP 0 LASTPIN (-3725 5525) $PN L19
J 0
(-3715 5535);
DISPLAY 0.489362 (-3715 5535);
PAINT MONO (-3715 5535);
FORCEPROP 0 LASTPIN (-3725 5475) $PN M21
J 0
(-3715 5485);
DISPLAY 0.489362 (-3715 5485);
PAINT MONO (-3715 5485);
FORCEPROP 0 LASTPIN (-3725 5425) $PN M20
J 0
(-3715 5435);
DISPLAY 0.489362 (-3715 5435);
PAINT MONO (-3715 5435);
FORCEPROP 0 LASTPIN (-3725 5375) $PN N21
J 0
(-3715 5385);
DISPLAY 0.489362 (-3715 5385);
PAINT MONO (-3715 5385);
FORCEPROP 0 LASTPIN (-3725 5325) $PN R19
J 0
(-3715 5335);
DISPLAY 0.489362 (-3715 5335);
PAINT MONO (-3715 5335);
FORCEPROP 0 LASTPIN (-3725 5275) $PN T21
J 0
(-3715 5285);
DISPLAY 0.489362 (-3715 5285);
PAINT MONO (-3715 5285);
FORCEPROP 0 LASTPIN (-3725 5225) $PN T20
J 0
(-3715 5235);
DISPLAY 0.489362 (-3715 5235);
PAINT MONO (-3715 5235);
FORCEPROP 0 LASTPIN (-3725 5175) $PN U21
J 0
(-3715 5185);
DISPLAY 0.489362 (-3715 5185);
PAINT MONO (-3715 5185);
FORCEPROP 0 LASTPIN (-3725 5075) $PN U19
J 0
(-3715 5085);
DISPLAY 0.489362 (-3715 5085);
PAINT MONO (-3715 5085);
FORCEPROP 0 LASTPIN (-3725 5025) $PN V21
J 0
(-3715 5035);
DISPLAY 0.489362 (-3715 5035);
PAINT MONO (-3715 5035);
FORCEPROP 0 LASTPIN (-3725 4975) $PN V20
J 0
(-3715 4985);
DISPLAY 0.489362 (-3715 4985);
PAINT MONO (-3715 4985);
FORCEPROP 0 LASTPIN (-3725 4925) $PN W21
J 0
(-3715 4935);
DISPLAY 0.489362 (-3715 4935);
PAINT MONO (-3715 4935);
FORCEPROP 0 LASTPIN (-3725 4875) $PN AA19
J 0
(-3715 4885);
DISPLAY 0.489362 (-3715 4885);
PAINT MONO (-3715 4885);
FORCEPROP 0 LASTPIN (-3725 4825) $PN AB21
J 0
(-3715 4835);
DISPLAY 0.489362 (-3715 4835);
PAINT MONO (-3715 4835);
FORCEPROP 0 LASTPIN (-3725 4775) $PN AB20
J 0
(-3715 4785);
DISPLAY 0.489362 (-3715 4785);
PAINT MONO (-3715 4785);
FORCEPROP 0 LASTPIN (-3725 4725) $PN AC21
J 0
(-3715 4735);
DISPLAY 0.489362 (-3715 4735);
PAINT MONO (-3715 4735);
FORCEPROP 0 LASTPIN (-3725 4625) $PN AC19
J 0
(-3715 4635);
DISPLAY 0.489362 (-3715 4635);
PAINT MONO (-3715 4635);
FORCEPROP 0 LASTPIN (-3725 4575) $PN AD21
J 0
(-3715 4585);
DISPLAY 0.489362 (-3715 4585);
PAINT MONO (-3715 4585);
FORCEPROP 0 LASTPIN (-3725 4525) $PN AD20
J 0
(-3715 4535);
DISPLAY 0.489362 (-3715 4535);
PAINT MONO (-3715 4535);
FORCEPROP 0 LASTPIN (-3725 4475) $PN AE21
J 0
(-3715 4485);
DISPLAY 0.489362 (-3715 4485);
PAINT MONO (-3715 4485);
FORCEPROP 0 LASTPIN (-3725 4425) $PN AG19
J 0
(-3715 4435);
DISPLAY 0.489362 (-3715 4435);
PAINT MONO (-3715 4435);
FORCEPROP 0 LASTPIN (-3725 4375) $PN AH21
J 0
(-3715 4385);
DISPLAY 0.489362 (-3715 4385);
PAINT MONO (-3715 4385);
FORCEPROP 0 LASTPIN (-3725 4325) $PN AH20
J 0
(-3715 4335);
DISPLAY 0.489362 (-3715 4335);
PAINT MONO (-3715 4335);
FORCEPROP 0 LASTPIN (-3725 4275) $PN AJ21
J 0
(-3715 4285);
DISPLAY 0.489362 (-3715 4285);
PAINT MONO (-3715 4285);
FORCEPROP 0 LASTPIN (-5325 5975) $PN G19
J 2
(-5335 5985);
DISPLAY 0.489362 (-5335 5985);
PAINT MONO (-5335 5985);
FORCEPROP 0 LASTPIN (-5325 5875) $PN N19
J 2
(-5335 5885);
DISPLAY 0.489362 (-5335 5885);
PAINT MONO (-5335 5885);
FORCEPROP 0 LASTPIN (-5325 5775) $PN W19
J 2
(-5335 5785);
DISPLAY 0.489362 (-5335 5785);
PAINT MONO (-5335 5785);
FORCEPROP 0 LASTPIN (-5325 5675) $PN AE19
J 2
(-5335 5685);
DISPLAY 0.489362 (-5335 5685);
PAINT MONO (-5335 5685);
FORCEPROP 0 LASTPIN (-5325 5575) $PN AL19
J 2
(-5335 5585);
DISPLAY 0.489362 (-5335 5585);
PAINT MONO (-5335 5585);
FORCEPROP 0 LASTPIN (-5325 5475) $PN J21
J 2
(-5335 5485);
DISPLAY 0.489362 (-5335 5485);
PAINT MONO (-5335 5485);
FORCEPROP 0 LASTPIN (-5325 5375) $PN R21
J 2
(-5335 5385);
DISPLAY 0.489362 (-5335 5385);
PAINT MONO (-5335 5385);
FORCEPROP 0 LASTPIN (-5325 5275) $PN AA21
J 2
(-5335 5285);
DISPLAY 0.489362 (-5335 5285);
PAINT MONO (-5335 5285);
FORCEPROP 0 LASTPIN (-5325 5175) $PN AG21
J 2
(-5335 5185);
DISPLAY 0.489362 (-5335 5185);
PAINT MONO (-5335 5185);
FORCEPROP 0 LASTPIN (-5325 5075) $PN AN21
J 2
(-5335 5085);
DISPLAY 0.489362 (-5335 5085);
PAINT MONO (-5335 5085);
FORCEPROP 0 LASTPIN (-5325 5925) $PN H20
J 2
(-5335 5935);
DISPLAY 0.489362 (-5335 5935);
PAINT MONO (-5335 5935);
FORCEPROP 0 LASTPIN (-5325 5825) $PN P20
J 2
(-5335 5835);
DISPLAY 0.489362 (-5335 5835);
PAINT MONO (-5335 5835);
FORCEPROP 0 LASTPIN (-5325 5725) $PN Y20
J 2
(-5335 5735);
DISPLAY 0.489362 (-5335 5735);
PAINT MONO (-5335 5735);
FORCEPROP 0 LASTPIN (-5325 5625) $PN AF20
J 2
(-5335 5635);
DISPLAY 0.489362 (-5335 5635);
PAINT MONO (-5335 5635);
FORCEPROP 0 LASTPIN (-5325 5525) $PN AM20
J 2
(-5335 5535);
DISPLAY 0.489362 (-5335 5535);
PAINT MONO (-5335 5535);
FORCEPROP 0 LASTPIN (-5325 5425) $PN H21
J 2
(-5335 5435);
DISPLAY 0.489362 (-5335 5435);
PAINT MONO (-5335 5435);
FORCEPROP 0 LASTPIN (-5325 5325) $PN P21
J 2
(-5335 5335);
DISPLAY 0.489362 (-5335 5335);
PAINT MONO (-5335 5335);
FORCEPROP 0 LASTPIN (-5325 5225) $PN Y21
J 2
(-5335 5235);
DISPLAY 0.489362 (-5335 5235);
PAINT MONO (-5335 5235);
FORCEPROP 0 LASTPIN (-5325 5125) $PN AF21
J 2
(-5335 5135);
DISPLAY 0.489362 (-5335 5135);
PAINT MONO (-5335 5135);
FORCEPROP 0 LASTPIN (-5325 5025) $PN AM21
J 2
(-5335 5035);
DISPLAY 0.489362 (-5335 5035);
PAINT MONO (-5335 5035);
FORCEPROP 0 LASTPIN (-5325 2575) $PN BC21
J 2
(-5335 2585);
DISPLAY 0.489362 (-5335 2585);
PAINT MONO (-5335 2585);
FORCEPROP 0 LASTPIN (-5325 2475) $PN BM21
J 2
(-5335 2485);
DISPLAY 0.489362 (-5335 2485);
PAINT MONO (-5335 2485);
FORCEPROP 0 LASTPIN (-5325 2425) $PN BN19
J 2
(-5335 2435);
DISPLAY 0.489362 (-5335 2435);
PAINT MONO (-5335 2435);
FORCEPROP 0 LASTPIN (-5325 2325) $PN BP20
J 2
(-5335 2335);
DISPLAY 0.489362 (-5335 2335);
PAINT MONO (-5335 2335);
FORCEPROP 0 LASTPIN (-5325 1425) $PN BL19
J 2
(-5335 1435);
DISPLAY 0.489362 (-5335 1435);
PAINT MONO (-5335 1435);
FORCEPROP 0 LASTPIN (-5325 1375) $PN BM20
J 2
(-5335 1385);
DISPLAY 0.489362 (-5335 1385);
PAINT MONO (-5335 1385);
FORCEPROP 0 LASTPIN (-5325 1275) $PN BR19
J 2
(-5335 1285);
DISPLAY 0.489362 (-5335 1285);
PAINT MONO (-5335 1285);
FORCEPROP 0 LASTPIN (-5325 3425) $PN BG21
J 2
(-5335 3435);
DISPLAY 0.489362 (-5335 3435);
PAINT MONO (-5335 3435);
FORCEPROP 0 LASTPIN (-5325 3375) $PN BH21
J 2
(-5335 3385);
DISPLAY 0.489362 (-5335 3385);
PAINT MONO (-5335 3385);
FORCEPROP 0 LASTPIN (-5325 3325) $PN BH20
J 2
(-5335 3335);
DISPLAY 0.489362 (-5335 3335);
PAINT MONO (-5335 3335);
FORCEPROP 0 LASTPIN (-5325 3275) $PN BJ19
J 2
(-5335 3285);
DISPLAY 0.489362 (-5335 3285);
PAINT MONO (-5335 3285);
FORCEPROP 0 LASTPIN (-5325 3225) $PN BJ21
J 2
(-5335 3235);
DISPLAY 0.489362 (-5335 3235);
PAINT MONO (-5335 3235);
FORCEPROP 0 LASTPIN (-5325 3175) $PN BK21
J 2
(-5335 3185);
DISPLAY 0.489362 (-5335 3185);
PAINT MONO (-5335 3185);
FORCEPROP 0 LASTPIN (-5325 3125) $PN BK20
J 2
(-5335 3135);
DISPLAY 0.489362 (-5335 3135);
PAINT MONO (-5335 3135);
FORCEPROP 0 LASTPIN (-3725 1925) $PN BY20
J 0
(-3715 1935);
DISPLAY 0.489362 (-3715 1935);
PAINT MONO (-3715 1935);
FORCEPROP 0 LASTPIN (-3725 1875) $PN CA21
J 0
(-3715 1885);
DISPLAY 0.489362 (-3715 1885);
PAINT MONO (-3715 1885);
FORCEPROP 0 LASTPIN (-3725 1825) $PN CA19
J 0
(-3715 1835);
DISPLAY 0.489362 (-3715 1835);
PAINT MONO (-3715 1835);
FORCEPROP 0 LASTPIN (-3725 1775) $PN CB21
J 0
(-3715 1785);
DISPLAY 0.489362 (-3715 1785);
PAINT MONO (-3715 1785);
FORCEPROP 0 LASTPIN (-3725 1725) $PN BT20
J 0
(-3715 1735);
DISPLAY 0.489362 (-3715 1735);
PAINT MONO (-3715 1735);
FORCEPROP 0 LASTPIN (-3725 1675) $PN BU21
J 0
(-3715 1685);
DISPLAY 0.489362 (-3715 1685);
PAINT MONO (-3715 1685);
FORCEPROP 0 LASTPIN (-3725 1625) $PN BU19
J 0
(-3715 1635);
DISPLAY 0.489362 (-3715 1635);
PAINT MONO (-3715 1635);
FORCEPROP 0 LASTPIN (-3725 1575) $PN BV21
J 0
(-3715 1585);
DISPLAY 0.489362 (-3715 1585);
PAINT MONO (-3715 1585);
FORCEPROP 0 LASTPIN (-3725 4175) $PN CB20
J 0
(-3715 4185);
DISPLAY 0.489362 (-3715 4185);
PAINT MONO (-3715 4185);
FORCEPROP 0 LASTPIN (-3725 4125) $PN CC21
J 0
(-3715 4135);
DISPLAY 0.489362 (-3715 4135);
PAINT MONO (-3715 4135);
FORCEPROP 0 LASTPIN (-3725 4075) $PN CC19
J 0
(-3715 4085);
DISPLAY 0.489362 (-3715 4085);
PAINT MONO (-3715 4085);
FORCEPROP 0 LASTPIN (-3725 4025) $PN CD21
J 0
(-3715 4035);
DISPLAY 0.489362 (-3715 4035);
PAINT MONO (-3715 4035);
FORCEPROP 0 LASTPIN (-3725 3975) $PN CF20
J 0
(-3715 3985);
DISPLAY 0.489362 (-3715 3985);
PAINT MONO (-3715 3985);
FORCEPROP 0 LASTPIN (-3725 3925) $PN CG21
J 0
(-3715 3935);
DISPLAY 0.489362 (-3715 3935);
PAINT MONO (-3715 3935);
FORCEPROP 0 LASTPIN (-3725 3875) $PN CG19
J 0
(-3715 3885);
DISPLAY 0.489362 (-3715 3885);
PAINT MONO (-3715 3885);
FORCEPROP 0 LASTPIN (-3725 3825) $PN CH21
J 0
(-3715 3835);
DISPLAY 0.489362 (-3715 3835);
PAINT MONO (-3715 3835);
FORCEPROP 0 LASTPIN (-3725 3725) $PN CH20
J 0
(-3715 3735);
DISPLAY 0.489362 (-3715 3735);
PAINT MONO (-3715 3735);
FORCEPROP 0 LASTPIN (-3725 3675) $PN CJ21
J 0
(-3715 3685);
DISPLAY 0.489362 (-3715 3685);
PAINT MONO (-3715 3685);
FORCEPROP 0 LASTPIN (-3725 3625) $PN CJ19
J 0
(-3715 3635);
DISPLAY 0.489362 (-3715 3635);
PAINT MONO (-3715 3635);
FORCEPROP 0 LASTPIN (-3725 3575) $PN CK21
J 0
(-3715 3585);
DISPLAY 0.489362 (-3715 3585);
PAINT MONO (-3715 3585);
FORCEPROP 0 LASTPIN (-3725 3525) $PN CM20
J 0
(-3715 3535);
DISPLAY 0.489362 (-3715 3535);
PAINT MONO (-3715 3535);
FORCEPROP 0 LASTPIN (-3725 3475) $PN CN21
J 0
(-3715 3485);
DISPLAY 0.489362 (-3715 3485);
PAINT MONO (-3715 3485);
FORCEPROP 0 LASTPIN (-3725 3425) $PN CN19
J 0
(-3715 3435);
DISPLAY 0.489362 (-3715 3435);
PAINT MONO (-3715 3435);
FORCEPROP 0 LASTPIN (-3725 3375) $PN CP21
J 0
(-3715 3385);
DISPLAY 0.489362 (-3715 3385);
PAINT MONO (-3715 3385);
FORCEPROP 0 LASTPIN (-3725 3275) $PN CP20
J 0
(-3715 3285);
DISPLAY 0.489362 (-3715 3285);
PAINT MONO (-3715 3285);
FORCEPROP 0 LASTPIN (-3725 3225) $PN CR21
J 0
(-3715 3235);
DISPLAY 0.489362 (-3715 3235);
PAINT MONO (-3715 3235);
FORCEPROP 0 LASTPIN (-3725 3175) $PN CR19
J 0
(-3715 3185);
DISPLAY 0.489362 (-3715 3185);
PAINT MONO (-3715 3185);
FORCEPROP 0 LASTPIN (-3725 3125) $PN CT21
J 0
(-3715 3135);
DISPLAY 0.489362 (-3715 3135);
PAINT MONO (-3715 3135);
FORCEPROP 0 LASTPIN (-3725 3075) $PN CV20
J 0
(-3715 3085);
DISPLAY 0.489362 (-3715 3085);
PAINT MONO (-3715 3085);
FORCEPROP 0 LASTPIN (-3725 3025) $PN CW21
J 0
(-3715 3035);
DISPLAY 0.489362 (-3715 3035);
PAINT MONO (-3715 3035);
FORCEPROP 0 LASTPIN (-3725 2975) $PN CW19
J 0
(-3715 2985);
DISPLAY 0.489362 (-3715 2985);
PAINT MONO (-3715 2985);
FORCEPROP 0 LASTPIN (-3725 2925) $PN CY21
J 0
(-3715 2935);
DISPLAY 0.489362 (-3715 2935);
PAINT MONO (-3715 2935);
FORCEPROP 0 LASTPIN (-3725 2825) $PN CY20
J 0
(-3715 2835);
DISPLAY 0.489362 (-3715 2835);
PAINT MONO (-3715 2835);
FORCEPROP 0 LASTPIN (-3725 2775) $PN DA21
J 0
(-3715 2785);
DISPLAY 0.489362 (-3715 2785);
PAINT MONO (-3715 2785);
FORCEPROP 0 LASTPIN (-3725 2725) $PN DA19
J 0
(-3715 2735);
DISPLAY 0.489362 (-3715 2735);
PAINT MONO (-3715 2735);
FORCEPROP 0 LASTPIN (-3725 2675) $PN DB21
J 0
(-3715 2685);
DISPLAY 0.489362 (-3715 2685);
PAINT MONO (-3715 2685);
FORCEPROP 0 LASTPIN (-3725 2625) $PN DD20
J 0
(-3715 2635);
DISPLAY 0.489362 (-3715 2635);
PAINT MONO (-3715 2635);
FORCEPROP 0 LASTPIN (-3725 2575) $PN DE21
J 0
(-3715 2585);
DISPLAY 0.489362 (-3715 2585);
PAINT MONO (-3715 2585);
FORCEPROP 0 LASTPIN (-3725 2525) $PN DE19
J 0
(-3715 2535);
DISPLAY 0.489362 (-3715 2535);
PAINT MONO (-3715 2535);
FORCEPROP 0 LASTPIN (-3725 2475) $PN DF21
J 0
(-3715 2485);
DISPLAY 0.489362 (-3715 2485);
PAINT MONO (-3715 2485);
FORCEPROP 0 LASTPIN (-5325 4925) $PN CD20
J 2
(-5335 4935);
DISPLAY 0.489362 (-5335 4935);
PAINT MONO (-5335 4935);
FORCEPROP 0 LASTPIN (-5325 4825) $PN CK20
J 2
(-5335 4835);
DISPLAY 0.489362 (-5335 4835);
PAINT MONO (-5335 4835);
FORCEPROP 0 LASTPIN (-5325 4725) $PN CT20
J 2
(-5335 4735);
DISPLAY 0.489362 (-5335 4735);
PAINT MONO (-5335 4735);
FORCEPROP 0 LASTPIN (-5325 4625) $PN DB20
J 2
(-5335 4635);
DISPLAY 0.489362 (-5335 4635);
PAINT MONO (-5335 4635);
FORCEPROP 0 LASTPIN (-5325 4525) $PN BY21
J 2
(-5335 4535);
DISPLAY 0.489362 (-5335 4535);
PAINT MONO (-5335 4535);
FORCEPROP 0 LASTPIN (-5325 4425) $PN CF21
J 2
(-5335 4435);
DISPLAY 0.489362 (-5335 4435);
PAINT MONO (-5335 4435);
FORCEPROP 0 LASTPIN (-5325 4325) $PN CM21
J 2
(-5335 4335);
DISPLAY 0.489362 (-5335 4335);
PAINT MONO (-5335 4335);
FORCEPROP 0 LASTPIN (-5325 4225) $PN CV21
J 2
(-5335 4235);
DISPLAY 0.489362 (-5335 4235);
PAINT MONO (-5335 4235);
FORCEPROP 0 LASTPIN (-5325 4125) $PN DD21
J 2
(-5335 4135);
DISPLAY 0.489362 (-5335 4135);
PAINT MONO (-5335 4135);
FORCEPROP 0 LASTPIN (-5325 4025) $PN BV20
J 2
(-5335 4035);
DISPLAY 0.489362 (-5335 4035);
PAINT MONO (-5335 4035);
FORCEPROP 0 LASTPIN (-5325 4875) $PN CE19
J 2
(-5335 4885);
DISPLAY 0.489362 (-5335 4885);
PAINT MONO (-5335 4885);
FORCEPROP 0 LASTPIN (-5325 4775) $PN CL19
J 2
(-5335 4785);
DISPLAY 0.489362 (-5335 4785);
PAINT MONO (-5335 4785);
FORCEPROP 0 LASTPIN (-5325 4675) $PN CU19
J 2
(-5335 4685);
DISPLAY 0.489362 (-5335 4685);
PAINT MONO (-5335 4685);
FORCEPROP 0 LASTPIN (-5325 4575) $PN DC19
J 2
(-5335 4585);
DISPLAY 0.489362 (-5335 4585);
PAINT MONO (-5335 4585);
FORCEPROP 0 LASTPIN (-5325 4475) $PN BW21
J 2
(-5335 4485);
DISPLAY 0.489362 (-5335 4485);
PAINT MONO (-5335 4485);
FORCEPROP 0 LASTPIN (-5325 4375) $PN CE21
J 2
(-5335 4385);
DISPLAY 0.489362 (-5335 4385);
PAINT MONO (-5335 4385);
FORCEPROP 0 LASTPIN (-5325 4275) $PN CL21
J 2
(-5335 4285);
DISPLAY 0.489362 (-5335 4285);
PAINT MONO (-5335 4285);
FORCEPROP 0 LASTPIN (-5325 4175) $PN CU21
J 2
(-5335 4185);
DISPLAY 0.489362 (-5335 4185);
PAINT MONO (-5335 4185);
FORCEPROP 0 LASTPIN (-5325 4075) $PN DC21
J 2
(-5335 4085);
DISPLAY 0.489362 (-5335 4085);
PAINT MONO (-5335 4085);
FORCEPROP 0 LASTPIN (-5325 3975) $PN BW19
J 2
(-5335 3985);
DISPLAY 0.489362 (-5335 3985);
PAINT MONO (-5335 3985);
FORCEPROP 0 LASTPIN (-5325 2225) $PN BL21
J 2
(-5335 2235);
DISPLAY 0.489362 (-5335 2235);
PAINT MONO (-5335 2235);
FORCEPROP 0 LASTPIN (-5325 1175) $PN BF21
J 2
(-5335 1185);
DISPLAY 0.489362 (-5335 1185);
PAINT MONO (-5335 1185);
FORCEPROP 2 LAST PART_TYPE SMLF
J 0
(-5175 6350);
DISPLAY 1.021277 (-5175 6350);
FORCEPROP 1 LAST MATERIAL IO
J 0
(-5170 6157);
DISPLAY 0.489362 (-5170 6157);
PAINT SKYBLUE (-5170 6157);
FORCEPROP 2 LAST VALUE SOCKET6096_13568-001
J 0
(-5175 6250);
DISPLAY 0.489362 (-5175 6250);
PAINT SKYBLUE (-5175 6250);
FORCEPROP 1 LAST PART_NUMBER DGA^6000030
J 0
(-5170 6284);
DISPLAY 0.489362 (-5170 6284);
PAINT SKYBLUE (-5170 6284);
FORCEPROP 2 LAST CDS_LIB pure_quanta
J 0
(-4525 3600);
DISPLAY INVISIBLE (-4525 3600);
FORCEPROP 1 LAST CDS_LMAN_SYM_OUTLINE -650,2525,650,-2525
J 0
(-4525 3600);
DISPLAY 0.468085 (-4525 3600);
PAINT GREEN (-4525 3600);
DISPLAY INVISIBLE (-4525 3600);
FORCEPROP 1 LAST NEEDS_NO_SIZE TRUE
J 0
(-4525 3600);
DISPLAY 0.723404 (-4525 3600);
PAINT GREEN (-4525 3600);
DISPLAY INVISIBLE (-4525 3600);
FORCEPROP 1 LAST PATH I159
J 0
(-4525 3600);
DISPLAY 0.723404 (-4525 3600);
PAINT GREEN (-4525 3600);
DISPLAY INVISIBLE (-4525 3600);
FORCEADD OFFPAGE..3
(-2525 6000);
FORCEPROP 2 LAST $XR0 93 
J 0
(-2311 6000);
DISPLAY 0.638298 (-2311 6000);
PAINT MONO (-2311 6000);
FORCEPROP 2 LAST PATH I160
J 0
(-2300 6050);
DISPLAY 1.021277 (-2300 6050);
DISPLAY INVISIBLE (-2300 6050);
FORCEPROP 1 LAST COMMENT_BODY TRUE
J 0
(-2575 5900);
DISPLAY 0.872340 (-2575 5900);
PAINT GREEN (-2575 5900);
DISPLAY INVISIBLE (-2575 5900);
FORCEPROP 1 LAST OFFPAGE TRUE
J 0
(-2200 5875);
DISPLAY 0.872340 (-2200 5875);
PAINT GREEN (-2200 5875);
DISPLAY INVISIBLE (-2200 5875);
FORCEPROP 2 LAST CDS_LIB mstr_standard
J 0
(-2525 6000);
DISPLAY 0.723404 (-2525 6000);
PAINT MONO (-2525 6000);
DISPLAY INVISIBLE (-2525 6000);
FORCEADD OFFPAGE..3
(-2525 4200);
FORCEPROP 2 LAST $XR0 93 
J 0
(-2311 4200);
DISPLAY 0.638298 (-2311 4200);
PAINT MONO (-2311 4200);
FORCEPROP 2 LAST PATH I161
J 0
(-2300 4250);
DISPLAY 1.021277 (-2300 4250);
DISPLAY INVISIBLE (-2300 4250);
FORCEPROP 1 LAST COMMENT_BODY TRUE
J 0
(-2575 4100);
DISPLAY 0.872340 (-2575 4100);
PAINT GREEN (-2575 4100);
DISPLAY INVISIBLE (-2575 4100);
FORCEPROP 1 LAST OFFPAGE TRUE
J 0
(-2200 4075);
DISPLAY 0.872340 (-2200 4075);
PAINT GREEN (-2200 4075);
DISPLAY INVISIBLE (-2200 4075);
FORCEPROP 2 LAST CDS_LIB mstr_standard
J 0
(-2525 4200);
DISPLAY 0.723404 (-2525 4200);
PAINT MONO (-2525 4200);
DISPLAY INVISIBLE (-2525 4200);
FORCEADD TAP..1
(-3250 5975);
FORCEPROP 3 LASTPIN (-3300 5975) SIG_NAME M_I_CPU0_SA_DQ<0>
J 0
(-3290 5985);
DISPLAY 0.659574 (-3290 5985);
PAINT MONO (-3290 5985);
DISPLAY INVISIBLE (-3290 5985);
FORCEPROP 1 LASTPIN (-3300 5975) BN 0
J 0
(-3312 5983);
DISPLAY 0.489362 (-3312 5983);
PAINT GREEN (-3312 5983);
FORCEPROP 2 LAST CDS_LIB mstr_standard
J 0
(-3250 5975);
DISPLAY 0.723404 (-3250 5975);
PAINT MONO (-3250 5975);
DISPLAY INVISIBLE (-3250 5975);
FORCEPROP 1 LAST BODY_TYPE PLUMBING
J 0
(-3250 6025);
DISPLAY 0.872340 (-3250 6025);
PAINT GREEN (-3250 6025);
DISPLAY INVISIBLE (-3250 6025);
FORCEPROP 1 LAST HDL_TAP TRUE
J 0
(-2925 5850);
DISPLAY 0.872340 (-2925 5850);
DISPLAY INVISIBLE (-2925 5850);
FORCEPROP 1 LAST PATH I162
J 0
(-3252 5975);
DISPLAY 0.872340 (-3252 5975);
PAINT GREEN (-3252 5975);
DISPLAY INVISIBLE (-3252 5975);
FORCEADD TAP..1
(-3250 5925);
FORCEPROP 3 LASTPIN (-3300 5925) SIG_NAME M_I_CPU0_SA_DQ<1>
J 0
(-3290 5935);
DISPLAY 0.659574 (-3290 5935);
PAINT MONO (-3290 5935);
DISPLAY INVISIBLE (-3290 5935);
FORCEPROP 1 LASTPIN (-3300 5925) BN 1
J 0
(-3312 5933);
DISPLAY 0.489362 (-3312 5933);
PAINT GREEN (-3312 5933);
FORCEPROP 2 LAST CDS_LIB mstr_standard
J 0
(-3250 5925);
DISPLAY 0.723404 (-3250 5925);
PAINT MONO (-3250 5925);
DISPLAY INVISIBLE (-3250 5925);
FORCEPROP 1 LAST BODY_TYPE PLUMBING
J 0
(-3250 5975);
DISPLAY 0.872340 (-3250 5975);
PAINT GREEN (-3250 5975);
DISPLAY INVISIBLE (-3250 5975);
FORCEPROP 1 LAST HDL_TAP TRUE
J 0
(-2925 5800);
DISPLAY 0.872340 (-2925 5800);
DISPLAY INVISIBLE (-2925 5800);
FORCEPROP 1 LAST PATH I163
J 0
(-3252 5925);
DISPLAY 0.872340 (-3252 5925);
PAINT GREEN (-3252 5925);
DISPLAY INVISIBLE (-3252 5925);
FORCEADD TAP..1
(-3250 5775);
FORCEPROP 3 LASTPIN (-3300 5775) SIG_NAME M_I_CPU0_SA_DQ<4>
J 0
(-3290 5785);
DISPLAY 0.659574 (-3290 5785);
PAINT MONO (-3290 5785);
DISPLAY INVISIBLE (-3290 5785);
FORCEPROP 1 LASTPIN (-3300 5775) BN 4
J 0
(-3312 5783);
DISPLAY 0.489362 (-3312 5783);
PAINT GREEN (-3312 5783);
FORCEPROP 2 LAST CDS_LIB mstr_standard
J 0
(-3250 5775);
DISPLAY 0.723404 (-3250 5775);
PAINT MONO (-3250 5775);
DISPLAY INVISIBLE (-3250 5775);
FORCEPROP 1 LAST BODY_TYPE PLUMBING
J 0
(-3250 5825);
DISPLAY 0.872340 (-3250 5825);
PAINT GREEN (-3250 5825);
DISPLAY INVISIBLE (-3250 5825);
FORCEPROP 1 LAST HDL_TAP TRUE
J 0
(-2925 5650);
DISPLAY 0.872340 (-2925 5650);
DISPLAY INVISIBLE (-2925 5650);
FORCEPROP 1 LAST PATH I164
J 0
(-3252 5775);
DISPLAY 0.872340 (-3252 5775);
PAINT GREEN (-3252 5775);
DISPLAY INVISIBLE (-3252 5775);
FORCEADD TAP..1
(-3250 5825);
FORCEPROP 3 LASTPIN (-3300 5825) SIG_NAME M_I_CPU0_SA_DQ<3>
J 0
(-3290 5835);
DISPLAY 0.659574 (-3290 5835);
PAINT MONO (-3290 5835);
DISPLAY INVISIBLE (-3290 5835);
FORCEPROP 1 LASTPIN (-3300 5825) BN 3
J 0
(-3312 5833);
DISPLAY 0.489362 (-3312 5833);
PAINT GREEN (-3312 5833);
FORCEPROP 2 LAST CDS_LIB mstr_standard
J 0
(-3250 5825);
DISPLAY 0.723404 (-3250 5825);
PAINT MONO (-3250 5825);
DISPLAY INVISIBLE (-3250 5825);
FORCEPROP 1 LAST BODY_TYPE PLUMBING
J 0
(-3250 5875);
DISPLAY 0.872340 (-3250 5875);
PAINT GREEN (-3250 5875);
DISPLAY INVISIBLE (-3250 5875);
FORCEPROP 1 LAST HDL_TAP TRUE
J 0
(-2925 5700);
DISPLAY 0.872340 (-2925 5700);
DISPLAY INVISIBLE (-2925 5700);
FORCEPROP 1 LAST PATH I165
J 0
(-3252 5825);
DISPLAY 0.872340 (-3252 5825);
PAINT GREEN (-3252 5825);
DISPLAY INVISIBLE (-3252 5825);
FORCEADD TAP..1
(-3250 5875);
FORCEPROP 3 LASTPIN (-3300 5875) SIG_NAME M_I_CPU0_SA_DQ<2>
J 0
(-3290 5885);
DISPLAY 0.659574 (-3290 5885);
PAINT MONO (-3290 5885);
DISPLAY INVISIBLE (-3290 5885);
FORCEPROP 1 LASTPIN (-3300 5875) BN 2
J 0
(-3312 5883);
DISPLAY 0.489362 (-3312 5883);
PAINT GREEN (-3312 5883);
FORCEPROP 2 LAST CDS_LIB mstr_standard
J 0
(-3250 5875);
DISPLAY 0.723404 (-3250 5875);
PAINT MONO (-3250 5875);
DISPLAY INVISIBLE (-3250 5875);
FORCEPROP 1 LAST BODY_TYPE PLUMBING
J 0
(-3250 5925);
DISPLAY 0.872340 (-3250 5925);
PAINT GREEN (-3250 5925);
DISPLAY INVISIBLE (-3250 5925);
FORCEPROP 1 LAST HDL_TAP TRUE
J 0
(-2925 5750);
DISPLAY 0.872340 (-2925 5750);
DISPLAY INVISIBLE (-2925 5750);
FORCEPROP 1 LAST PATH I166
J 0
(-3252 5875);
DISPLAY 0.872340 (-3252 5875);
PAINT GREEN (-3252 5875);
DISPLAY INVISIBLE (-3252 5875);
FORCEADD TAP..1
(-3250 5675);
FORCEPROP 3 LASTPIN (-3300 5675) SIG_NAME M_I_CPU0_SA_DQ<6>
J 0
(-3290 5685);
DISPLAY 0.659574 (-3290 5685);
PAINT MONO (-3290 5685);
DISPLAY INVISIBLE (-3290 5685);
FORCEPROP 1 LASTPIN (-3300 5675) BN 6
J 0
(-3312 5683);
DISPLAY 0.489362 (-3312 5683);
PAINT GREEN (-3312 5683);
FORCEPROP 2 LAST CDS_LIB mstr_standard
J 0
(-3250 5675);
DISPLAY 0.723404 (-3250 5675);
PAINT MONO (-3250 5675);
DISPLAY INVISIBLE (-3250 5675);
FORCEPROP 1 LAST BODY_TYPE PLUMBING
J 0
(-3250 5725);
DISPLAY 0.872340 (-3250 5725);
PAINT GREEN (-3250 5725);
DISPLAY INVISIBLE (-3250 5725);
FORCEPROP 1 LAST HDL_TAP TRUE
J 0
(-2925 5550);
DISPLAY 0.872340 (-2925 5550);
DISPLAY INVISIBLE (-2925 5550);
FORCEPROP 1 LAST PATH I167
J 0
(-3252 5675);
DISPLAY 0.872340 (-3252 5675);
PAINT GREEN (-3252 5675);
DISPLAY INVISIBLE (-3252 5675);
FORCEADD TAP..1
(-3250 5725);
FORCEPROP 3 LASTPIN (-3300 5725) SIG_NAME M_I_CPU0_SA_DQ<5>
J 0
(-3290 5735);
DISPLAY 0.659574 (-3290 5735);
PAINT MONO (-3290 5735);
DISPLAY INVISIBLE (-3290 5735);
FORCEPROP 1 LASTPIN (-3300 5725) BN 5
J 0
(-3312 5733);
DISPLAY 0.489362 (-3312 5733);
PAINT GREEN (-3312 5733);
FORCEPROP 2 LAST CDS_LIB mstr_standard
J 0
(-3250 5725);
DISPLAY 0.723404 (-3250 5725);
PAINT MONO (-3250 5725);
DISPLAY INVISIBLE (-3250 5725);
FORCEPROP 1 LAST BODY_TYPE PLUMBING
J 0
(-3250 5775);
DISPLAY 0.872340 (-3250 5775);
PAINT GREEN (-3250 5775);
DISPLAY INVISIBLE (-3250 5775);
FORCEPROP 1 LAST HDL_TAP TRUE
J 0
(-2925 5600);
DISPLAY 0.872340 (-2925 5600);
DISPLAY INVISIBLE (-2925 5600);
FORCEPROP 1 LAST PATH I168
J 0
(-3252 5725);
DISPLAY 0.872340 (-3252 5725);
PAINT GREEN (-3252 5725);
DISPLAY INVISIBLE (-3252 5725);
FORCEADD TAP..1
(-3250 5525);
FORCEPROP 3 LASTPIN (-3300 5525) SIG_NAME M_I_CPU0_SA_DQ<8>
J 0
(-3290 5535);
DISPLAY 0.659574 (-3290 5535);
PAINT MONO (-3290 5535);
DISPLAY INVISIBLE (-3290 5535);
FORCEPROP 1 LASTPIN (-3300 5525) BN 8
J 0
(-3312 5533);
DISPLAY 0.489362 (-3312 5533);
PAINT GREEN (-3312 5533);
FORCEPROP 2 LAST CDS_LIB mstr_standard
J 0
(-3250 5525);
DISPLAY 0.723404 (-3250 5525);
PAINT MONO (-3250 5525);
DISPLAY INVISIBLE (-3250 5525);
FORCEPROP 1 LAST BODY_TYPE PLUMBING
J 0
(-3250 5575);
DISPLAY 0.872340 (-3250 5575);
PAINT GREEN (-3250 5575);
DISPLAY INVISIBLE (-3250 5575);
FORCEPROP 1 LAST HDL_TAP TRUE
J 0
(-2925 5400);
DISPLAY 0.872340 (-2925 5400);
DISPLAY INVISIBLE (-2925 5400);
FORCEPROP 1 LAST PATH I169
J 0
(-3252 5525);
DISPLAY 0.872340 (-3252 5525);
PAINT GREEN (-3252 5525);
DISPLAY INVISIBLE (-3252 5525);
FORCEADD TAP..1
(-3250 5625);
FORCEPROP 3 LASTPIN (-3300 5625) SIG_NAME M_I_CPU0_SA_DQ<7>
J 0
(-3290 5635);
DISPLAY 0.659574 (-3290 5635);
PAINT MONO (-3290 5635);
DISPLAY INVISIBLE (-3290 5635);
FORCEPROP 1 LASTPIN (-3300 5625) BN 7
J 0
(-3312 5633);
DISPLAY 0.489362 (-3312 5633);
PAINT GREEN (-3312 5633);
FORCEPROP 2 LAST CDS_LIB mstr_standard
J 0
(-3250 5625);
DISPLAY 0.723404 (-3250 5625);
PAINT MONO (-3250 5625);
DISPLAY INVISIBLE (-3250 5625);
FORCEPROP 1 LAST BODY_TYPE PLUMBING
J 0
(-3250 5675);
DISPLAY 0.872340 (-3250 5675);
PAINT GREEN (-3250 5675);
DISPLAY INVISIBLE (-3250 5675);
FORCEPROP 1 LAST HDL_TAP TRUE
J 0
(-2925 5500);
DISPLAY 0.872340 (-2925 5500);
DISPLAY INVISIBLE (-2925 5500);
FORCEPROP 1 LAST PATH I170
J 0
(-3252 5625);
DISPLAY 0.872340 (-3252 5625);
PAINT GREEN (-3252 5625);
DISPLAY INVISIBLE (-3252 5625);
FORCEADD TAP..1
(-3250 5425);
FORCEPROP 3 LASTPIN (-3300 5425) SIG_NAME M_I_CPU0_SA_DQ<10>
J 0
(-3290 5435);
DISPLAY 0.659574 (-3290 5435);
PAINT MONO (-3290 5435);
DISPLAY INVISIBLE (-3290 5435);
FORCEPROP 1 LASTPIN (-3300 5425) BN 10
J 0
(-3312 5433);
DISPLAY 0.489362 (-3312 5433);
PAINT GREEN (-3312 5433);
FORCEPROP 2 LAST CDS_LIB mstr_standard
J 0
(-3250 5425);
DISPLAY 0.723404 (-3250 5425);
PAINT MONO (-3250 5425);
DISPLAY INVISIBLE (-3250 5425);
FORCEPROP 1 LAST BODY_TYPE PLUMBING
J 0
(-3250 5475);
DISPLAY 0.872340 (-3250 5475);
PAINT GREEN (-3250 5475);
DISPLAY INVISIBLE (-3250 5475);
FORCEPROP 1 LAST HDL_TAP TRUE
J 0
(-2925 5300);
DISPLAY 0.872340 (-2925 5300);
DISPLAY INVISIBLE (-2925 5300);
FORCEPROP 1 LAST PATH I171
J 0
(-3252 5425);
DISPLAY 0.872340 (-3252 5425);
PAINT GREEN (-3252 5425);
DISPLAY INVISIBLE (-3252 5425);
FORCEADD TAP..1
(-3250 5475);
FORCEPROP 3 LASTPIN (-3300 5475) SIG_NAME M_I_CPU0_SA_DQ<9>
J 0
(-3290 5485);
DISPLAY 0.659574 (-3290 5485);
PAINT MONO (-3290 5485);
DISPLAY INVISIBLE (-3290 5485);
FORCEPROP 1 LASTPIN (-3300 5475) BN 9
J 0
(-3312 5483);
DISPLAY 0.489362 (-3312 5483);
PAINT GREEN (-3312 5483);
FORCEPROP 2 LAST CDS_LIB mstr_standard
J 0
(-3250 5475);
DISPLAY 0.723404 (-3250 5475);
PAINT MONO (-3250 5475);
DISPLAY INVISIBLE (-3250 5475);
FORCEPROP 1 LAST BODY_TYPE PLUMBING
J 0
(-3250 5525);
DISPLAY 0.872340 (-3250 5525);
PAINT GREEN (-3250 5525);
DISPLAY INVISIBLE (-3250 5525);
FORCEPROP 1 LAST HDL_TAP TRUE
J 0
(-2925 5350);
DISPLAY 0.872340 (-2925 5350);
DISPLAY INVISIBLE (-2925 5350);
FORCEPROP 1 LAST PATH I172
J 0
(-3252 5475);
DISPLAY 0.872340 (-3252 5475);
PAINT GREEN (-3252 5475);
DISPLAY INVISIBLE (-3252 5475);
FORCEADD TAP..1
(-3250 5275);
FORCEPROP 3 LASTPIN (-3300 5275) SIG_NAME M_I_CPU0_SA_DQ<13>
J 0
(-3290 5285);
DISPLAY 0.659574 (-3290 5285);
PAINT MONO (-3290 5285);
DISPLAY INVISIBLE (-3290 5285);
FORCEPROP 1 LASTPIN (-3300 5275) BN 13
J 0
(-3312 5283);
DISPLAY 0.489362 (-3312 5283);
PAINT GREEN (-3312 5283);
FORCEPROP 2 LAST CDS_LIB mstr_standard
J 0
(-3250 5275);
DISPLAY 0.723404 (-3250 5275);
PAINT MONO (-3250 5275);
DISPLAY INVISIBLE (-3250 5275);
FORCEPROP 1 LAST BODY_TYPE PLUMBING
J 0
(-3250 5325);
DISPLAY 0.872340 (-3250 5325);
PAINT GREEN (-3250 5325);
DISPLAY INVISIBLE (-3250 5325);
FORCEPROP 1 LAST HDL_TAP TRUE
J 0
(-2925 5150);
DISPLAY 0.872340 (-2925 5150);
DISPLAY INVISIBLE (-2925 5150);
FORCEPROP 1 LAST PATH I173
J 0
(-3252 5275);
DISPLAY 0.872340 (-3252 5275);
PAINT GREEN (-3252 5275);
DISPLAY INVISIBLE (-3252 5275);
FORCEADD TAP..1
(-3250 5325);
FORCEPROP 3 LASTPIN (-3300 5325) SIG_NAME M_I_CPU0_SA_DQ<12>
J 0
(-3290 5335);
DISPLAY 0.659574 (-3290 5335);
PAINT MONO (-3290 5335);
DISPLAY INVISIBLE (-3290 5335);
FORCEPROP 1 LASTPIN (-3300 5325) BN 12
J 0
(-3312 5333);
DISPLAY 0.489362 (-3312 5333);
PAINT GREEN (-3312 5333);
FORCEPROP 2 LAST CDS_LIB mstr_standard
J 0
(-3250 5325);
DISPLAY 0.723404 (-3250 5325);
PAINT MONO (-3250 5325);
DISPLAY INVISIBLE (-3250 5325);
FORCEPROP 1 LAST BODY_TYPE PLUMBING
J 0
(-3250 5375);
DISPLAY 0.872340 (-3250 5375);
PAINT GREEN (-3250 5375);
DISPLAY INVISIBLE (-3250 5375);
FORCEPROP 1 LAST HDL_TAP TRUE
J 0
(-2925 5200);
DISPLAY 0.872340 (-2925 5200);
DISPLAY INVISIBLE (-2925 5200);
FORCEPROP 1 LAST PATH I174
J 0
(-3252 5325);
DISPLAY 0.872340 (-3252 5325);
PAINT GREEN (-3252 5325);
DISPLAY INVISIBLE (-3252 5325);
FORCEADD TAP..1
(-3250 5375);
FORCEPROP 3 LASTPIN (-3300 5375) SIG_NAME M_I_CPU0_SA_DQ<11>
J 0
(-3290 5385);
DISPLAY 0.659574 (-3290 5385);
PAINT MONO (-3290 5385);
DISPLAY INVISIBLE (-3290 5385);
FORCEPROP 1 LASTPIN (-3300 5375) BN 11
J 0
(-3312 5383);
DISPLAY 0.489362 (-3312 5383);
PAINT GREEN (-3312 5383);
FORCEPROP 2 LAST CDS_LIB mstr_standard
J 0
(-3250 5375);
DISPLAY 0.723404 (-3250 5375);
PAINT MONO (-3250 5375);
DISPLAY INVISIBLE (-3250 5375);
FORCEPROP 1 LAST BODY_TYPE PLUMBING
J 0
(-3250 5425);
DISPLAY 0.872340 (-3250 5425);
PAINT GREEN (-3250 5425);
DISPLAY INVISIBLE (-3250 5425);
FORCEPROP 1 LAST HDL_TAP TRUE
J 0
(-2925 5250);
DISPLAY 0.872340 (-2925 5250);
DISPLAY INVISIBLE (-2925 5250);
FORCEPROP 1 LAST PATH I175
J 0
(-3252 5375);
DISPLAY 0.872340 (-3252 5375);
PAINT GREEN (-3252 5375);
DISPLAY INVISIBLE (-3252 5375);
FORCEADD TAP..1
(-3250 5225);
FORCEPROP 3 LASTPIN (-3300 5225) SIG_NAME M_I_CPU0_SA_DQ<14>
J 0
(-3290 5235);
DISPLAY 0.659574 (-3290 5235);
PAINT MONO (-3290 5235);
DISPLAY INVISIBLE (-3290 5235);
FORCEPROP 1 LASTPIN (-3300 5225) BN 14
J 0
(-3312 5233);
DISPLAY 0.489362 (-3312 5233);
PAINT GREEN (-3312 5233);
FORCEPROP 2 LAST CDS_LIB mstr_standard
J 0
(-3250 5225);
DISPLAY 0.723404 (-3250 5225);
PAINT MONO (-3250 5225);
DISPLAY INVISIBLE (-3250 5225);
FORCEPROP 1 LAST BODY_TYPE PLUMBING
J 0
(-3250 5275);
DISPLAY 0.872340 (-3250 5275);
PAINT GREEN (-3250 5275);
DISPLAY INVISIBLE (-3250 5275);
FORCEPROP 1 LAST HDL_TAP TRUE
J 0
(-2925 5100);
DISPLAY 0.872340 (-2925 5100);
DISPLAY INVISIBLE (-2925 5100);
FORCEPROP 1 LAST PATH I176
J 0
(-3252 5225);
DISPLAY 0.872340 (-3252 5225);
PAINT GREEN (-3252 5225);
DISPLAY INVISIBLE (-3252 5225);
FORCEADD TAP..1
(-3250 5175);
FORCEPROP 3 LASTPIN (-3300 5175) SIG_NAME M_I_CPU0_SA_DQ<15>
J 0
(-3290 5185);
DISPLAY 0.659574 (-3290 5185);
PAINT MONO (-3290 5185);
DISPLAY INVISIBLE (-3290 5185);
FORCEPROP 1 LASTPIN (-3300 5175) BN 15
J 0
(-3312 5183);
DISPLAY 0.489362 (-3312 5183);
PAINT GREEN (-3312 5183);
FORCEPROP 2 LAST CDS_LIB mstr_standard
J 0
(-3250 5175);
DISPLAY 0.723404 (-3250 5175);
PAINT MONO (-3250 5175);
DISPLAY INVISIBLE (-3250 5175);
FORCEPROP 1 LAST BODY_TYPE PLUMBING
J 0
(-3250 5225);
DISPLAY 0.872340 (-3250 5225);
PAINT GREEN (-3250 5225);
DISPLAY INVISIBLE (-3250 5225);
FORCEPROP 1 LAST HDL_TAP TRUE
J 0
(-2925 5050);
DISPLAY 0.872340 (-2925 5050);
DISPLAY INVISIBLE (-2925 5050);
FORCEPROP 1 LAST PATH I177
J 0
(-3252 5175);
DISPLAY 0.872340 (-3252 5175);
PAINT GREEN (-3252 5175);
DISPLAY INVISIBLE (-3252 5175);
FORCEADD TAP..1
(-3250 5075);
FORCEPROP 3 LASTPIN (-3300 5075) SIG_NAME M_I_CPU0_SA_DQ<16>
J 0
(-3290 5085);
DISPLAY 0.659574 (-3290 5085);
PAINT MONO (-3290 5085);
DISPLAY INVISIBLE (-3290 5085);
FORCEPROP 1 LASTPIN (-3300 5075) BN 16
J 0
(-3312 5083);
DISPLAY 0.489362 (-3312 5083);
PAINT GREEN (-3312 5083);
FORCEPROP 2 LAST CDS_LIB mstr_standard
J 0
(-3250 5075);
DISPLAY 0.723404 (-3250 5075);
PAINT MONO (-3250 5075);
DISPLAY INVISIBLE (-3250 5075);
FORCEPROP 1 LAST BODY_TYPE PLUMBING
J 0
(-3250 5125);
DISPLAY 0.872340 (-3250 5125);
PAINT GREEN (-3250 5125);
DISPLAY INVISIBLE (-3250 5125);
FORCEPROP 1 LAST HDL_TAP TRUE
J 0
(-2925 4950);
DISPLAY 0.872340 (-2925 4950);
DISPLAY INVISIBLE (-2925 4950);
FORCEPROP 1 LAST PATH I178
J 0
(-3252 5075);
DISPLAY 0.872340 (-3252 5075);
PAINT GREEN (-3252 5075);
DISPLAY INVISIBLE (-3252 5075);
FORCEADD TAP..1
(-3250 5025);
FORCEPROP 3 LASTPIN (-3300 5025) SIG_NAME M_I_CPU0_SA_DQ<17>
J 0
(-3290 5035);
DISPLAY 0.659574 (-3290 5035);
PAINT MONO (-3290 5035);
DISPLAY INVISIBLE (-3290 5035);
FORCEPROP 1 LASTPIN (-3300 5025) BN 17
J 0
(-3312 5033);
DISPLAY 0.489362 (-3312 5033);
PAINT GREEN (-3312 5033);
FORCEPROP 2 LAST CDS_LIB mstr_standard
J 0
(-3250 5025);
DISPLAY 0.723404 (-3250 5025);
PAINT MONO (-3250 5025);
DISPLAY INVISIBLE (-3250 5025);
FORCEPROP 1 LAST BODY_TYPE PLUMBING
J 0
(-3250 5075);
DISPLAY 0.872340 (-3250 5075);
PAINT GREEN (-3250 5075);
DISPLAY INVISIBLE (-3250 5075);
FORCEPROP 1 LAST HDL_TAP TRUE
J 0
(-2925 4900);
DISPLAY 0.872340 (-2925 4900);
DISPLAY INVISIBLE (-2925 4900);
FORCEPROP 1 LAST PATH I179
J 0
(-3252 5025);
DISPLAY 0.872340 (-3252 5025);
PAINT GREEN (-3252 5025);
DISPLAY INVISIBLE (-3252 5025);
FORCEADD TAP..1
(-3250 4875);
FORCEPROP 3 LASTPIN (-3300 4875) SIG_NAME M_I_CPU0_SA_DQ<20>
J 0
(-3290 4885);
DISPLAY 0.659574 (-3290 4885);
PAINT MONO (-3290 4885);
DISPLAY INVISIBLE (-3290 4885);
FORCEPROP 1 LASTPIN (-3300 4875) BN 20
J 0
(-3312 4883);
DISPLAY 0.489362 (-3312 4883);
PAINT GREEN (-3312 4883);
FORCEPROP 2 LAST CDS_LIB mstr_standard
J 0
(-3250 4875);
DISPLAY 0.723404 (-3250 4875);
PAINT MONO (-3250 4875);
DISPLAY INVISIBLE (-3250 4875);
FORCEPROP 1 LAST BODY_TYPE PLUMBING
J 0
(-3250 4925);
DISPLAY 0.872340 (-3250 4925);
PAINT GREEN (-3250 4925);
DISPLAY INVISIBLE (-3250 4925);
FORCEPROP 1 LAST HDL_TAP TRUE
J 0
(-2925 4750);
DISPLAY 0.872340 (-2925 4750);
DISPLAY INVISIBLE (-2925 4750);
FORCEPROP 1 LAST PATH I180
J 0
(-3252 4875);
DISPLAY 0.872340 (-3252 4875);
PAINT GREEN (-3252 4875);
DISPLAY INVISIBLE (-3252 4875);
FORCEADD TAP..1
(-3250 4925);
FORCEPROP 3 LASTPIN (-3300 4925) SIG_NAME M_I_CPU0_SA_DQ<19>
J 0
(-3290 4935);
DISPLAY 0.659574 (-3290 4935);
PAINT MONO (-3290 4935);
DISPLAY INVISIBLE (-3290 4935);
FORCEPROP 1 LASTPIN (-3300 4925) BN 19
J 0
(-3312 4933);
DISPLAY 0.489362 (-3312 4933);
PAINT GREEN (-3312 4933);
FORCEPROP 2 LAST CDS_LIB mstr_standard
J 0
(-3250 4925);
DISPLAY 0.723404 (-3250 4925);
PAINT MONO (-3250 4925);
DISPLAY INVISIBLE (-3250 4925);
FORCEPROP 1 LAST BODY_TYPE PLUMBING
J 0
(-3250 4975);
DISPLAY 0.872340 (-3250 4975);
PAINT GREEN (-3250 4975);
DISPLAY INVISIBLE (-3250 4975);
FORCEPROP 1 LAST HDL_TAP TRUE
J 0
(-2925 4800);
DISPLAY 0.872340 (-2925 4800);
DISPLAY INVISIBLE (-2925 4800);
FORCEPROP 1 LAST PATH I181
J 0
(-3252 4925);
DISPLAY 0.872340 (-3252 4925);
PAINT GREEN (-3252 4925);
DISPLAY INVISIBLE (-3252 4925);
FORCEADD TAP..1
(-3250 4975);
FORCEPROP 3 LASTPIN (-3300 4975) SIG_NAME M_I_CPU0_SA_DQ<18>
J 0
(-3290 4985);
DISPLAY 0.659574 (-3290 4985);
PAINT MONO (-3290 4985);
DISPLAY INVISIBLE (-3290 4985);
FORCEPROP 1 LASTPIN (-3300 4975) BN 18
J 0
(-3312 4983);
DISPLAY 0.489362 (-3312 4983);
PAINT GREEN (-3312 4983);
FORCEPROP 2 LAST CDS_LIB mstr_standard
J 0
(-3250 4975);
DISPLAY 0.723404 (-3250 4975);
PAINT MONO (-3250 4975);
DISPLAY INVISIBLE (-3250 4975);
FORCEPROP 1 LAST BODY_TYPE PLUMBING
J 0
(-3250 5025);
DISPLAY 0.872340 (-3250 5025);
PAINT GREEN (-3250 5025);
DISPLAY INVISIBLE (-3250 5025);
FORCEPROP 1 LAST HDL_TAP TRUE
J 0
(-2925 4850);
DISPLAY 0.872340 (-2925 4850);
DISPLAY INVISIBLE (-2925 4850);
FORCEPROP 1 LAST PATH I182
J 0
(-3252 4975);
DISPLAY 0.872340 (-3252 4975);
PAINT GREEN (-3252 4975);
DISPLAY INVISIBLE (-3252 4975);
FORCEADD TAP..1
(-3250 4775);
FORCEPROP 3 LASTPIN (-3300 4775) SIG_NAME M_I_CPU0_SA_DQ<22>
J 0
(-3290 4785);
DISPLAY 0.659574 (-3290 4785);
PAINT MONO (-3290 4785);
DISPLAY INVISIBLE (-3290 4785);
FORCEPROP 1 LASTPIN (-3300 4775) BN 22
J 0
(-3312 4783);
DISPLAY 0.489362 (-3312 4783);
PAINT GREEN (-3312 4783);
FORCEPROP 2 LAST CDS_LIB mstr_standard
J 0
(-3250 4775);
DISPLAY 0.723404 (-3250 4775);
PAINT MONO (-3250 4775);
DISPLAY INVISIBLE (-3250 4775);
FORCEPROP 1 LAST BODY_TYPE PLUMBING
J 0
(-3250 4825);
DISPLAY 0.872340 (-3250 4825);
PAINT GREEN (-3250 4825);
DISPLAY INVISIBLE (-3250 4825);
FORCEPROP 1 LAST HDL_TAP TRUE
J 0
(-2925 4650);
DISPLAY 0.872340 (-2925 4650);
DISPLAY INVISIBLE (-2925 4650);
FORCEPROP 1 LAST PATH I183
J 0
(-3252 4775);
DISPLAY 0.872340 (-3252 4775);
PAINT GREEN (-3252 4775);
DISPLAY INVISIBLE (-3252 4775);
FORCEADD TAP..1
(-3250 4825);
FORCEPROP 3 LASTPIN (-3300 4825) SIG_NAME M_I_CPU0_SA_DQ<21>
J 0
(-3290 4835);
DISPLAY 0.659574 (-3290 4835);
PAINT MONO (-3290 4835);
DISPLAY INVISIBLE (-3290 4835);
FORCEPROP 1 LASTPIN (-3300 4825) BN 21
J 0
(-3312 4833);
DISPLAY 0.489362 (-3312 4833);
PAINT GREEN (-3312 4833);
FORCEPROP 2 LAST CDS_LIB mstr_standard
J 0
(-3250 4825);
DISPLAY 0.723404 (-3250 4825);
PAINT MONO (-3250 4825);
DISPLAY INVISIBLE (-3250 4825);
FORCEPROP 1 LAST BODY_TYPE PLUMBING
J 0
(-3250 4875);
DISPLAY 0.872340 (-3250 4875);
PAINT GREEN (-3250 4875);
DISPLAY INVISIBLE (-3250 4875);
FORCEPROP 1 LAST HDL_TAP TRUE
J 0
(-2925 4700);
DISPLAY 0.872340 (-2925 4700);
DISPLAY INVISIBLE (-2925 4700);
FORCEPROP 1 LAST PATH I184
J 0
(-3252 4825);
DISPLAY 0.872340 (-3252 4825);
PAINT GREEN (-3252 4825);
DISPLAY INVISIBLE (-3252 4825);
FORCEADD TAP..1
(-3250 4725);
FORCEPROP 3 LASTPIN (-3300 4725) SIG_NAME M_I_CPU0_SA_DQ<23>
J 0
(-3290 4735);
DISPLAY 0.659574 (-3290 4735);
PAINT MONO (-3290 4735);
DISPLAY INVISIBLE (-3290 4735);
FORCEPROP 1 LASTPIN (-3300 4725) BN 23
J 0
(-3312 4733);
DISPLAY 0.489362 (-3312 4733);
PAINT GREEN (-3312 4733);
FORCEPROP 2 LAST CDS_LIB mstr_standard
J 0
(-3250 4725);
DISPLAY 0.723404 (-3250 4725);
PAINT MONO (-3250 4725);
DISPLAY INVISIBLE (-3250 4725);
FORCEPROP 1 LAST BODY_TYPE PLUMBING
J 0
(-3250 4775);
DISPLAY 0.872340 (-3250 4775);
PAINT GREEN (-3250 4775);
DISPLAY INVISIBLE (-3250 4775);
FORCEPROP 1 LAST HDL_TAP TRUE
J 0
(-2925 4600);
DISPLAY 0.872340 (-2925 4600);
DISPLAY INVISIBLE (-2925 4600);
FORCEPROP 1 LAST PATH I185
J 0
(-3252 4725);
DISPLAY 0.872340 (-3252 4725);
PAINT GREEN (-3252 4725);
DISPLAY INVISIBLE (-3252 4725);
FORCEADD TAP..1
(-3250 4625);
FORCEPROP 3 LASTPIN (-3300 4625) SIG_NAME M_I_CPU0_SA_DQ<24>
J 0
(-3290 4635);
DISPLAY 0.659574 (-3290 4635);
PAINT MONO (-3290 4635);
DISPLAY INVISIBLE (-3290 4635);
FORCEPROP 1 LASTPIN (-3300 4625) BN 24
J 0
(-3312 4633);
DISPLAY 0.489362 (-3312 4633);
PAINT GREEN (-3312 4633);
FORCEPROP 2 LAST CDS_LIB mstr_standard
J 0
(-3250 4625);
DISPLAY 0.723404 (-3250 4625);
PAINT MONO (-3250 4625);
DISPLAY INVISIBLE (-3250 4625);
FORCEPROP 1 LAST BODY_TYPE PLUMBING
J 0
(-3250 4675);
DISPLAY 0.872340 (-3250 4675);
PAINT GREEN (-3250 4675);
DISPLAY INVISIBLE (-3250 4675);
FORCEPROP 1 LAST HDL_TAP TRUE
J 0
(-2925 4500);
DISPLAY 0.872340 (-2925 4500);
DISPLAY INVISIBLE (-2925 4500);
FORCEPROP 1 LAST PATH I186
J 0
(-3252 4625);
DISPLAY 0.872340 (-3252 4625);
PAINT GREEN (-3252 4625);
DISPLAY INVISIBLE (-3252 4625);
FORCEADD TAP..1
(-3250 4525);
FORCEPROP 3 LASTPIN (-3300 4525) SIG_NAME M_I_CPU0_SA_DQ<26>
J 0
(-3290 4535);
DISPLAY 0.659574 (-3290 4535);
PAINT MONO (-3290 4535);
DISPLAY INVISIBLE (-3290 4535);
FORCEPROP 1 LASTPIN (-3300 4525) BN 26
J 0
(-3312 4533);
DISPLAY 0.489362 (-3312 4533);
PAINT GREEN (-3312 4533);
FORCEPROP 2 LAST CDS_LIB mstr_standard
J 0
(-3250 4525);
DISPLAY 0.723404 (-3250 4525);
PAINT MONO (-3250 4525);
DISPLAY INVISIBLE (-3250 4525);
FORCEPROP 1 LAST BODY_TYPE PLUMBING
J 0
(-3250 4575);
DISPLAY 0.872340 (-3250 4575);
PAINT GREEN (-3250 4575);
DISPLAY INVISIBLE (-3250 4575);
FORCEPROP 1 LAST HDL_TAP TRUE
J 0
(-2925 4400);
DISPLAY 0.872340 (-2925 4400);
DISPLAY INVISIBLE (-2925 4400);
FORCEPROP 1 LAST PATH I187
J 0
(-3252 4525);
DISPLAY 0.872340 (-3252 4525);
PAINT GREEN (-3252 4525);
DISPLAY INVISIBLE (-3252 4525);
FORCEADD TAP..1
(-3250 4575);
FORCEPROP 3 LASTPIN (-3300 4575) SIG_NAME M_I_CPU0_SA_DQ<25>
J 0
(-3290 4585);
DISPLAY 0.659574 (-3290 4585);
PAINT MONO (-3290 4585);
DISPLAY INVISIBLE (-3290 4585);
FORCEPROP 1 LASTPIN (-3300 4575) BN 25
J 0
(-3312 4583);
DISPLAY 0.489362 (-3312 4583);
PAINT GREEN (-3312 4583);
FORCEPROP 2 LAST CDS_LIB mstr_standard
J 0
(-3250 4575);
DISPLAY 0.723404 (-3250 4575);
PAINT MONO (-3250 4575);
DISPLAY INVISIBLE (-3250 4575);
FORCEPROP 1 LAST BODY_TYPE PLUMBING
J 0
(-3250 4625);
DISPLAY 0.872340 (-3250 4625);
PAINT GREEN (-3250 4625);
DISPLAY INVISIBLE (-3250 4625);
FORCEPROP 1 LAST HDL_TAP TRUE
J 0
(-2925 4450);
DISPLAY 0.872340 (-2925 4450);
DISPLAY INVISIBLE (-2925 4450);
FORCEPROP 1 LAST PATH I188
J 0
(-3252 4575);
DISPLAY 0.872340 (-3252 4575);
PAINT GREEN (-3252 4575);
DISPLAY INVISIBLE (-3252 4575);
FORCEADD TAP..1
(-3250 4375);
FORCEPROP 3 LASTPIN (-3300 4375) SIG_NAME M_I_CPU0_SA_DQ<29>
J 0
(-3290 4385);
DISPLAY 0.659574 (-3290 4385);
PAINT MONO (-3290 4385);
DISPLAY INVISIBLE (-3290 4385);
FORCEPROP 1 LASTPIN (-3300 4375) BN 29
J 0
(-3312 4383);
DISPLAY 0.489362 (-3312 4383);
PAINT GREEN (-3312 4383);
FORCEPROP 2 LAST CDS_LIB mstr_standard
J 0
(-3250 4375);
DISPLAY 0.723404 (-3250 4375);
PAINT MONO (-3250 4375);
DISPLAY INVISIBLE (-3250 4375);
FORCEPROP 1 LAST BODY_TYPE PLUMBING
J 0
(-3250 4425);
DISPLAY 0.872340 (-3250 4425);
PAINT GREEN (-3250 4425);
DISPLAY INVISIBLE (-3250 4425);
FORCEPROP 1 LAST HDL_TAP TRUE
J 0
(-2925 4250);
DISPLAY 0.872340 (-2925 4250);
DISPLAY INVISIBLE (-2925 4250);
FORCEPROP 1 LAST PATH I189
J 0
(-3252 4375);
DISPLAY 0.872340 (-3252 4375);
PAINT GREEN (-3252 4375);
DISPLAY INVISIBLE (-3252 4375);
FORCEADD TAP..1
(-3250 4425);
FORCEPROP 3 LASTPIN (-3300 4425) SIG_NAME M_I_CPU0_SA_DQ<28>
J 0
(-3290 4435);
DISPLAY 0.659574 (-3290 4435);
PAINT MONO (-3290 4435);
DISPLAY INVISIBLE (-3290 4435);
FORCEPROP 1 LASTPIN (-3300 4425) BN 28
J 0
(-3312 4433);
DISPLAY 0.489362 (-3312 4433);
PAINT GREEN (-3312 4433);
FORCEPROP 2 LAST CDS_LIB mstr_standard
J 0
(-3250 4425);
DISPLAY 0.723404 (-3250 4425);
PAINT MONO (-3250 4425);
DISPLAY INVISIBLE (-3250 4425);
FORCEPROP 1 LAST BODY_TYPE PLUMBING
J 0
(-3250 4475);
DISPLAY 0.872340 (-3250 4475);
PAINT GREEN (-3250 4475);
DISPLAY INVISIBLE (-3250 4475);
FORCEPROP 1 LAST HDL_TAP TRUE
J 0
(-2925 4300);
DISPLAY 0.872340 (-2925 4300);
DISPLAY INVISIBLE (-2925 4300);
FORCEPROP 1 LAST PATH I190
J 0
(-3252 4425);
DISPLAY 0.872340 (-3252 4425);
PAINT GREEN (-3252 4425);
DISPLAY INVISIBLE (-3252 4425);
FORCEADD TAP..1
(-3250 4475);
FORCEPROP 3 LASTPIN (-3300 4475) SIG_NAME M_I_CPU0_SA_DQ<27>
J 0
(-3290 4485);
DISPLAY 0.659574 (-3290 4485);
PAINT MONO (-3290 4485);
DISPLAY INVISIBLE (-3290 4485);
FORCEPROP 1 LASTPIN (-3300 4475) BN 27
J 0
(-3312 4483);
DISPLAY 0.489362 (-3312 4483);
PAINT GREEN (-3312 4483);
FORCEPROP 2 LAST CDS_LIB mstr_standard
J 0
(-3250 4475);
DISPLAY 0.723404 (-3250 4475);
PAINT MONO (-3250 4475);
DISPLAY INVISIBLE (-3250 4475);
FORCEPROP 1 LAST BODY_TYPE PLUMBING
J 0
(-3250 4525);
DISPLAY 0.872340 (-3250 4525);
PAINT GREEN (-3250 4525);
DISPLAY INVISIBLE (-3250 4525);
FORCEPROP 1 LAST HDL_TAP TRUE
J 0
(-2925 4350);
DISPLAY 0.872340 (-2925 4350);
DISPLAY INVISIBLE (-2925 4350);
FORCEPROP 1 LAST PATH I191
J 0
(-3252 4475);
DISPLAY 0.872340 (-3252 4475);
PAINT GREEN (-3252 4475);
DISPLAY INVISIBLE (-3252 4475);
FORCEADD TAP..1
(-3250 4325);
FORCEPROP 3 LASTPIN (-3300 4325) SIG_NAME M_I_CPU0_SA_DQ<30>
J 0
(-3290 4335);
DISPLAY 0.659574 (-3290 4335);
PAINT MONO (-3290 4335);
DISPLAY INVISIBLE (-3290 4335);
FORCEPROP 1 LASTPIN (-3300 4325) BN 30
J 0
(-3312 4333);
DISPLAY 0.489362 (-3312 4333);
PAINT GREEN (-3312 4333);
FORCEPROP 2 LAST CDS_LIB mstr_standard
J 0
(-3250 4325);
DISPLAY 0.723404 (-3250 4325);
PAINT MONO (-3250 4325);
DISPLAY INVISIBLE (-3250 4325);
FORCEPROP 1 LAST BODY_TYPE PLUMBING
J 0
(-3250 4375);
DISPLAY 0.872340 (-3250 4375);
PAINT GREEN (-3250 4375);
DISPLAY INVISIBLE (-3250 4375);
FORCEPROP 1 LAST HDL_TAP TRUE
J 0
(-2925 4200);
DISPLAY 0.872340 (-2925 4200);
DISPLAY INVISIBLE (-2925 4200);
FORCEPROP 1 LAST PATH I192
J 0
(-3252 4325);
DISPLAY 0.872340 (-3252 4325);
PAINT GREEN (-3252 4325);
DISPLAY INVISIBLE (-3252 4325);
FORCEADD TAP..1
(-3250 4275);
FORCEPROP 3 LASTPIN (-3300 4275) SIG_NAME M_I_CPU0_SA_DQ<31>
J 0
(-3290 4285);
DISPLAY 0.659574 (-3290 4285);
PAINT MONO (-3290 4285);
DISPLAY INVISIBLE (-3290 4285);
FORCEPROP 1 LASTPIN (-3300 4275) BN 31
J 0
(-3312 4283);
DISPLAY 0.489362 (-3312 4283);
PAINT GREEN (-3312 4283);
FORCEPROP 2 LAST CDS_LIB mstr_standard
J 0
(-3250 4275);
DISPLAY 0.723404 (-3250 4275);
PAINT MONO (-3250 4275);
DISPLAY INVISIBLE (-3250 4275);
FORCEPROP 1 LAST BODY_TYPE PLUMBING
J 0
(-3250 4325);
DISPLAY 0.872340 (-3250 4325);
PAINT GREEN (-3250 4325);
DISPLAY INVISIBLE (-3250 4325);
FORCEPROP 1 LAST HDL_TAP TRUE
J 0
(-2925 4150);
DISPLAY 0.872340 (-2925 4150);
DISPLAY INVISIBLE (-2925 4150);
FORCEPROP 1 LAST PATH I193
J 0
(-3252 4275);
DISPLAY 0.872340 (-3252 4275);
PAINT GREEN (-3252 4275);
DISPLAY INVISIBLE (-3252 4275);
FORCEADD TAP..1
(-3250 4175);
FORCEPROP 3 LASTPIN (-3300 4175) SIG_NAME M_I_CPU0_SB_DQ<0>
J 0
(-3290 4185);
DISPLAY 0.659574 (-3290 4185);
PAINT MONO (-3290 4185);
DISPLAY INVISIBLE (-3290 4185);
FORCEPROP 1 LASTPIN (-3300 4175) BN 0
J 0
(-3312 4183);
DISPLAY 0.489362 (-3312 4183);
PAINT GREEN (-3312 4183);
FORCEPROP 2 LAST CDS_LIB mstr_standard
J 0
(-3250 4175);
DISPLAY 0.723404 (-3250 4175);
PAINT MONO (-3250 4175);
DISPLAY INVISIBLE (-3250 4175);
FORCEPROP 1 LAST BODY_TYPE PLUMBING
J 0
(-3250 4225);
DISPLAY 0.872340 (-3250 4225);
PAINT GREEN (-3250 4225);
DISPLAY INVISIBLE (-3250 4225);
FORCEPROP 1 LAST HDL_TAP TRUE
J 0
(-2925 4050);
DISPLAY 0.872340 (-2925 4050);
DISPLAY INVISIBLE (-2925 4050);
FORCEPROP 1 LAST PATH I194
J 0
(-3252 4175);
DISPLAY 0.872340 (-3252 4175);
PAINT GREEN (-3252 4175);
DISPLAY INVISIBLE (-3252 4175);
FORCEADD TAP..1
(-3250 4125);
FORCEPROP 3 LASTPIN (-3300 4125) SIG_NAME M_I_CPU0_SB_DQ<1>
J 0
(-3290 4135);
DISPLAY 0.659574 (-3290 4135);
PAINT MONO (-3290 4135);
DISPLAY INVISIBLE (-3290 4135);
FORCEPROP 1 LASTPIN (-3300 4125) BN 1
J 0
(-3312 4133);
DISPLAY 0.489362 (-3312 4133);
PAINT GREEN (-3312 4133);
FORCEPROP 2 LAST CDS_LIB mstr_standard
J 0
(-3250 4125);
DISPLAY 0.723404 (-3250 4125);
PAINT MONO (-3250 4125);
DISPLAY INVISIBLE (-3250 4125);
FORCEPROP 1 LAST BODY_TYPE PLUMBING
J 0
(-3250 4175);
DISPLAY 0.872340 (-3250 4175);
PAINT GREEN (-3250 4175);
DISPLAY INVISIBLE (-3250 4175);
FORCEPROP 1 LAST HDL_TAP TRUE
J 0
(-2925 4000);
DISPLAY 0.872340 (-2925 4000);
DISPLAY INVISIBLE (-2925 4000);
FORCEPROP 1 LAST PATH I195
J 0
(-3252 4125);
DISPLAY 0.872340 (-3252 4125);
PAINT GREEN (-3252 4125);
DISPLAY INVISIBLE (-3252 4125);
FORCEADD OFFPAGE..6
R 2
(-2650 2425);
FORCEPROP 2 LAST $XR0 93 
J 0
(-2436 2425);
DISPLAY 0.638298 (-2436 2425);
PAINT MONO (-2436 2425);
FORCEPROP 2 LAST PATH I196
J 0
(-2425 2475);
DISPLAY 1.021277 (-2425 2475);
DISPLAY INVISIBLE (-2425 2475);
FORCEPROP 1 LAST COMMENT_BODY TRUE
J 2
(-2750 2350);
DISPLAY 0.872340 (-2750 2350);
PAINT GREEN (-2750 2350);
DISPLAY INVISIBLE (-2750 2350);
FORCEPROP 1 LAST OFFPAGE TRUE
J 2
(-2975 2300);
DISPLAY 0.872340 (-2975 2300);
PAINT GREEN (-2975 2300);
DISPLAY INVISIBLE (-2975 2300);
FORCEPROP 2 LAST CDS_LIB mstr_standard
J 2
(-2650 2425);
DISPLAY 0.723404 (-2650 2425);
PAINT MONO (-2650 2425);
DISPLAY INVISIBLE (-2650 2425);
FORCEADD TAP..1
(-3250 3975);
FORCEPROP 3 LASTPIN (-3300 3975) SIG_NAME M_I_CPU0_SB_DQ<4>
J 0
(-3290 3985);
DISPLAY 0.659574 (-3290 3985);
PAINT MONO (-3290 3985);
DISPLAY INVISIBLE (-3290 3985);
FORCEPROP 1 LASTPIN (-3300 3975) BN 4
J 0
(-3312 3983);
DISPLAY 0.489362 (-3312 3983);
PAINT GREEN (-3312 3983);
FORCEPROP 2 LAST CDS_LIB mstr_standard
J 0
(-3250 3975);
DISPLAY 0.723404 (-3250 3975);
PAINT MONO (-3250 3975);
DISPLAY INVISIBLE (-3250 3975);
FORCEPROP 1 LAST BODY_TYPE PLUMBING
J 0
(-3250 4025);
DISPLAY 0.872340 (-3250 4025);
PAINT GREEN (-3250 4025);
DISPLAY INVISIBLE (-3250 4025);
FORCEPROP 1 LAST HDL_TAP TRUE
J 0
(-2925 3850);
DISPLAY 0.872340 (-2925 3850);
DISPLAY INVISIBLE (-2925 3850);
FORCEPROP 1 LAST PATH I197
J 0
(-3252 3975);
DISPLAY 0.872340 (-3252 3975);
PAINT GREEN (-3252 3975);
DISPLAY INVISIBLE (-3252 3975);
FORCEADD TAP..1
(-3250 4075);
FORCEPROP 3 LASTPIN (-3300 4075) SIG_NAME M_I_CPU0_SB_DQ<2>
J 0
(-3290 4085);
DISPLAY 0.659574 (-3290 4085);
PAINT MONO (-3290 4085);
DISPLAY INVISIBLE (-3290 4085);
FORCEPROP 1 LASTPIN (-3300 4075) BN 2
J 0
(-3312 4083);
DISPLAY 0.489362 (-3312 4083);
PAINT GREEN (-3312 4083);
FORCEPROP 2 LAST CDS_LIB mstr_standard
J 0
(-3250 4075);
DISPLAY 0.723404 (-3250 4075);
PAINT MONO (-3250 4075);
DISPLAY INVISIBLE (-3250 4075);
FORCEPROP 1 LAST BODY_TYPE PLUMBING
J 0
(-3250 4125);
DISPLAY 0.872340 (-3250 4125);
PAINT GREEN (-3250 4125);
DISPLAY INVISIBLE (-3250 4125);
FORCEPROP 1 LAST HDL_TAP TRUE
J 0
(-2925 3950);
DISPLAY 0.872340 (-2925 3950);
DISPLAY INVISIBLE (-2925 3950);
FORCEPROP 1 LAST PATH I198
J 0
(-3252 4075);
DISPLAY 0.872340 (-3252 4075);
PAINT GREEN (-3252 4075);
DISPLAY INVISIBLE (-3252 4075);
FORCEADD TAP..1
(-3250 4025);
FORCEPROP 3 LASTPIN (-3300 4025) SIG_NAME M_I_CPU0_SB_DQ<3>
J 0
(-3290 4035);
DISPLAY 0.659574 (-3290 4035);
PAINT MONO (-3290 4035);
DISPLAY INVISIBLE (-3290 4035);
FORCEPROP 1 LASTPIN (-3300 4025) BN 3
J 0
(-3312 4033);
DISPLAY 0.489362 (-3312 4033);
PAINT GREEN (-3312 4033);
FORCEPROP 2 LAST CDS_LIB mstr_standard
J 0
(-3250 4025);
DISPLAY 0.723404 (-3250 4025);
PAINT MONO (-3250 4025);
DISPLAY INVISIBLE (-3250 4025);
FORCEPROP 1 LAST BODY_TYPE PLUMBING
J 0
(-3250 4075);
DISPLAY 0.872340 (-3250 4075);
PAINT GREEN (-3250 4075);
DISPLAY INVISIBLE (-3250 4075);
FORCEPROP 1 LAST HDL_TAP TRUE
J 0
(-2925 3900);
DISPLAY 0.872340 (-2925 3900);
DISPLAY INVISIBLE (-2925 3900);
FORCEPROP 1 LAST PATH I199
J 0
(-3252 4025);
DISPLAY 0.872340 (-3252 4025);
PAINT GREEN (-3252 4025);
DISPLAY INVISIBLE (-3252 4025);
FORCEADD TAP..1
(-3250 3925);
FORCEPROP 3 LASTPIN (-3300 3925) SIG_NAME M_I_CPU0_SB_DQ<5>
J 0
(-3290 3935);
DISPLAY 0.659574 (-3290 3935);
PAINT MONO (-3290 3935);
DISPLAY INVISIBLE (-3290 3935);
FORCEPROP 1 LASTPIN (-3300 3925) BN 5
J 0
(-3312 3933);
DISPLAY 0.489362 (-3312 3933);
PAINT GREEN (-3312 3933);
FORCEPROP 2 LAST CDS_LIB mstr_standard
J 0
(-3250 3925);
DISPLAY 0.723404 (-3250 3925);
PAINT MONO (-3250 3925);
DISPLAY INVISIBLE (-3250 3925);
FORCEPROP 1 LAST BODY_TYPE PLUMBING
J 0
(-3250 3975);
DISPLAY 0.872340 (-3250 3975);
PAINT GREEN (-3250 3975);
DISPLAY INVISIBLE (-3250 3975);
FORCEPROP 1 LAST HDL_TAP TRUE
J 0
(-2925 3800);
DISPLAY 0.872340 (-2925 3800);
DISPLAY INVISIBLE (-2925 3800);
FORCEPROP 1 LAST PATH I200
J 0
(-3252 3925);
DISPLAY 0.872340 (-3252 3925);
PAINT GREEN (-3252 3925);
DISPLAY INVISIBLE (-3252 3925);
FORCEADD TAP..1
(-3250 3875);
FORCEPROP 3 LASTPIN (-3300 3875) SIG_NAME M_I_CPU0_SB_DQ<6>
J 0
(-3290 3885);
DISPLAY 0.659574 (-3290 3885);
PAINT MONO (-3290 3885);
DISPLAY INVISIBLE (-3290 3885);
FORCEPROP 1 LASTPIN (-3300 3875) BN 6
J 0
(-3312 3883);
DISPLAY 0.489362 (-3312 3883);
PAINT GREEN (-3312 3883);
FORCEPROP 2 LAST CDS_LIB mstr_standard
J 0
(-3250 3875);
DISPLAY 0.723404 (-3250 3875);
PAINT MONO (-3250 3875);
DISPLAY INVISIBLE (-3250 3875);
FORCEPROP 1 LAST BODY_TYPE PLUMBING
J 0
(-3250 3925);
DISPLAY 0.872340 (-3250 3925);
PAINT GREEN (-3250 3925);
DISPLAY INVISIBLE (-3250 3925);
FORCEPROP 1 LAST HDL_TAP TRUE
J 0
(-2925 3750);
DISPLAY 0.872340 (-2925 3750);
DISPLAY INVISIBLE (-2925 3750);
FORCEPROP 1 LAST PATH I201
J 0
(-3252 3875);
DISPLAY 0.872340 (-3252 3875);
PAINT GREEN (-3252 3875);
DISPLAY INVISIBLE (-3252 3875);
FORCEADD TAP..1
(-3250 3825);
FORCEPROP 3 LASTPIN (-3300 3825) SIG_NAME M_I_CPU0_SB_DQ<7>
J 0
(-3290 3835);
DISPLAY 0.659574 (-3290 3835);
PAINT MONO (-3290 3835);
DISPLAY INVISIBLE (-3290 3835);
FORCEPROP 1 LASTPIN (-3300 3825) BN 7
J 0
(-3312 3833);
DISPLAY 0.489362 (-3312 3833);
PAINT GREEN (-3312 3833);
FORCEPROP 2 LAST CDS_LIB mstr_standard
J 0
(-3250 3825);
DISPLAY 0.723404 (-3250 3825);
PAINT MONO (-3250 3825);
DISPLAY INVISIBLE (-3250 3825);
FORCEPROP 1 LAST BODY_TYPE PLUMBING
J 0
(-3250 3875);
DISPLAY 0.872340 (-3250 3875);
PAINT GREEN (-3250 3875);
DISPLAY INVISIBLE (-3250 3875);
FORCEPROP 1 LAST HDL_TAP TRUE
J 0
(-2925 3700);
DISPLAY 0.872340 (-2925 3700);
DISPLAY INVISIBLE (-2925 3700);
FORCEPROP 1 LAST PATH I202
J 0
(-3252 3825);
DISPLAY 0.872340 (-3252 3825);
PAINT GREEN (-3252 3825);
DISPLAY INVISIBLE (-3252 3825);
FORCEADD TAP..1
(-3250 3725);
FORCEPROP 3 LASTPIN (-3300 3725) SIG_NAME M_I_CPU0_SB_DQ<8>
J 0
(-3290 3735);
DISPLAY 0.659574 (-3290 3735);
PAINT MONO (-3290 3735);
DISPLAY INVISIBLE (-3290 3735);
FORCEPROP 1 LASTPIN (-3300 3725) BN 8
J 0
(-3312 3733);
DISPLAY 0.489362 (-3312 3733);
PAINT GREEN (-3312 3733);
FORCEPROP 2 LAST CDS_LIB mstr_standard
J 0
(-3250 3725);
DISPLAY 0.723404 (-3250 3725);
PAINT MONO (-3250 3725);
DISPLAY INVISIBLE (-3250 3725);
FORCEPROP 1 LAST BODY_TYPE PLUMBING
J 0
(-3250 3775);
DISPLAY 0.872340 (-3250 3775);
PAINT GREEN (-3250 3775);
DISPLAY INVISIBLE (-3250 3775);
FORCEPROP 1 LAST HDL_TAP TRUE
J 0
(-2925 3600);
DISPLAY 0.872340 (-2925 3600);
DISPLAY INVISIBLE (-2925 3600);
FORCEPROP 1 LAST PATH I203
J 0
(-3252 3725);
DISPLAY 0.872340 (-3252 3725);
PAINT GREEN (-3252 3725);
DISPLAY INVISIBLE (-3252 3725);
FORCEADD TAP..1
(-3250 3675);
FORCEPROP 3 LASTPIN (-3300 3675) SIG_NAME M_I_CPU0_SB_DQ<9>
J 0
(-3290 3685);
DISPLAY 0.659574 (-3290 3685);
PAINT MONO (-3290 3685);
DISPLAY INVISIBLE (-3290 3685);
FORCEPROP 1 LASTPIN (-3300 3675) BN 9
J 0
(-3312 3683);
DISPLAY 0.489362 (-3312 3683);
PAINT GREEN (-3312 3683);
FORCEPROP 2 LAST CDS_LIB mstr_standard
J 0
(-3250 3675);
DISPLAY 0.723404 (-3250 3675);
PAINT MONO (-3250 3675);
DISPLAY INVISIBLE (-3250 3675);
FORCEPROP 1 LAST BODY_TYPE PLUMBING
J 0
(-3250 3725);
DISPLAY 0.872340 (-3250 3725);
PAINT GREEN (-3250 3725);
DISPLAY INVISIBLE (-3250 3725);
FORCEPROP 1 LAST HDL_TAP TRUE
J 0
(-2925 3550);
DISPLAY 0.872340 (-2925 3550);
DISPLAY INVISIBLE (-2925 3550);
FORCEPROP 1 LAST PATH I204
J 0
(-3252 3675);
DISPLAY 0.872340 (-3252 3675);
PAINT GREEN (-3252 3675);
DISPLAY INVISIBLE (-3252 3675);
FORCEADD TAP..1
(-3250 3625);
FORCEPROP 3 LASTPIN (-3300 3625) SIG_NAME M_I_CPU0_SB_DQ<10>
J 0
(-3290 3635);
DISPLAY 0.659574 (-3290 3635);
PAINT MONO (-3290 3635);
DISPLAY INVISIBLE (-3290 3635);
FORCEPROP 1 LASTPIN (-3300 3625) BN 10
J 0
(-3312 3633);
DISPLAY 0.489362 (-3312 3633);
PAINT GREEN (-3312 3633);
FORCEPROP 2 LAST CDS_LIB mstr_standard
J 0
(-3250 3625);
DISPLAY 0.723404 (-3250 3625);
PAINT MONO (-3250 3625);
DISPLAY INVISIBLE (-3250 3625);
FORCEPROP 1 LAST BODY_TYPE PLUMBING
J 0
(-3250 3675);
DISPLAY 0.872340 (-3250 3675);
PAINT GREEN (-3250 3675);
DISPLAY INVISIBLE (-3250 3675);
FORCEPROP 1 LAST HDL_TAP TRUE
J 0
(-2925 3500);
DISPLAY 0.872340 (-2925 3500);
DISPLAY INVISIBLE (-2925 3500);
FORCEPROP 1 LAST PATH I205
J 0
(-3252 3625);
DISPLAY 0.872340 (-3252 3625);
PAINT GREEN (-3252 3625);
DISPLAY INVISIBLE (-3252 3625);
FORCEADD TAP..1
(-3250 3575);
FORCEPROP 3 LASTPIN (-3300 3575) SIG_NAME M_I_CPU0_SB_DQ<11>
J 0
(-3290 3585);
DISPLAY 0.659574 (-3290 3585);
PAINT MONO (-3290 3585);
DISPLAY INVISIBLE (-3290 3585);
FORCEPROP 1 LASTPIN (-3300 3575) BN 11
J 0
(-3312 3583);
DISPLAY 0.489362 (-3312 3583);
PAINT GREEN (-3312 3583);
FORCEPROP 2 LAST CDS_LIB mstr_standard
J 0
(-3250 3575);
DISPLAY 0.723404 (-3250 3575);
PAINT MONO (-3250 3575);
DISPLAY INVISIBLE (-3250 3575);
FORCEPROP 1 LAST BODY_TYPE PLUMBING
J 0
(-3250 3625);
DISPLAY 0.872340 (-3250 3625);
PAINT GREEN (-3250 3625);
DISPLAY INVISIBLE (-3250 3625);
FORCEPROP 1 LAST HDL_TAP TRUE
J 0
(-2925 3450);
DISPLAY 0.872340 (-2925 3450);
DISPLAY INVISIBLE (-2925 3450);
FORCEPROP 1 LAST PATH I206
J 0
(-3252 3575);
DISPLAY 0.872340 (-3252 3575);
PAINT GREEN (-3252 3575);
DISPLAY INVISIBLE (-3252 3575);
FORCEADD TAP..1
(-3250 3525);
FORCEPROP 3 LASTPIN (-3300 3525) SIG_NAME M_I_CPU0_SB_DQ<12>
J 0
(-3290 3535);
DISPLAY 0.659574 (-3290 3535);
PAINT MONO (-3290 3535);
DISPLAY INVISIBLE (-3290 3535);
FORCEPROP 1 LASTPIN (-3300 3525) BN 12
J 0
(-3312 3533);
DISPLAY 0.489362 (-3312 3533);
PAINT GREEN (-3312 3533);
FORCEPROP 2 LAST CDS_LIB mstr_standard
J 0
(-3250 3525);
DISPLAY 0.723404 (-3250 3525);
PAINT MONO (-3250 3525);
DISPLAY INVISIBLE (-3250 3525);
FORCEPROP 1 LAST BODY_TYPE PLUMBING
J 0
(-3250 3575);
DISPLAY 0.872340 (-3250 3575);
PAINT GREEN (-3250 3575);
DISPLAY INVISIBLE (-3250 3575);
FORCEPROP 1 LAST HDL_TAP TRUE
J 0
(-2925 3400);
DISPLAY 0.872340 (-2925 3400);
DISPLAY INVISIBLE (-2925 3400);
FORCEPROP 1 LAST PATH I207
J 0
(-3252 3525);
DISPLAY 0.872340 (-3252 3525);
PAINT GREEN (-3252 3525);
DISPLAY INVISIBLE (-3252 3525);
FORCEADD TAP..1
(-3250 3475);
FORCEPROP 3 LASTPIN (-3300 3475) SIG_NAME M_I_CPU0_SB_DQ<13>
J 0
(-3290 3485);
DISPLAY 0.659574 (-3290 3485);
PAINT MONO (-3290 3485);
DISPLAY INVISIBLE (-3290 3485);
FORCEPROP 1 LASTPIN (-3300 3475) BN 13
J 0
(-3312 3483);
DISPLAY 0.489362 (-3312 3483);
PAINT GREEN (-3312 3483);
FORCEPROP 2 LAST CDS_LIB mstr_standard
J 0
(-3250 3475);
DISPLAY 0.723404 (-3250 3475);
PAINT MONO (-3250 3475);
DISPLAY INVISIBLE (-3250 3475);
FORCEPROP 1 LAST BODY_TYPE PLUMBING
J 0
(-3250 3525);
DISPLAY 0.872340 (-3250 3525);
PAINT GREEN (-3250 3525);
DISPLAY INVISIBLE (-3250 3525);
FORCEPROP 1 LAST HDL_TAP TRUE
J 0
(-2925 3350);
DISPLAY 0.872340 (-2925 3350);
DISPLAY INVISIBLE (-2925 3350);
FORCEPROP 1 LAST PATH I208
J 0
(-3252 3475);
DISPLAY 0.872340 (-3252 3475);
PAINT GREEN (-3252 3475);
DISPLAY INVISIBLE (-3252 3475);
FORCEADD TAP..1
(-3250 3375);
FORCEPROP 3 LASTPIN (-3300 3375) SIG_NAME M_I_CPU0_SB_DQ<15>
J 0
(-3290 3385);
DISPLAY 0.659574 (-3290 3385);
PAINT MONO (-3290 3385);
DISPLAY INVISIBLE (-3290 3385);
FORCEPROP 1 LASTPIN (-3300 3375) BN 15
J 0
(-3312 3383);
DISPLAY 0.489362 (-3312 3383);
PAINT GREEN (-3312 3383);
FORCEPROP 2 LAST CDS_LIB mstr_standard
J 0
(-3250 3375);
DISPLAY 0.723404 (-3250 3375);
PAINT MONO (-3250 3375);
DISPLAY INVISIBLE (-3250 3375);
FORCEPROP 1 LAST BODY_TYPE PLUMBING
J 0
(-3250 3425);
DISPLAY 0.872340 (-3250 3425);
PAINT GREEN (-3250 3425);
DISPLAY INVISIBLE (-3250 3425);
FORCEPROP 1 LAST HDL_TAP TRUE
J 0
(-2925 3250);
DISPLAY 0.872340 (-2925 3250);
DISPLAY INVISIBLE (-2925 3250);
FORCEPROP 1 LAST PATH I209
J 0
(-3252 3375);
DISPLAY 0.872340 (-3252 3375);
PAINT GREEN (-3252 3375);
DISPLAY INVISIBLE (-3252 3375);
FORCEADD TAP..1
(-3250 3425);
FORCEPROP 3 LASTPIN (-3300 3425) SIG_NAME M_I_CPU0_SB_DQ<14>
J 0
(-3290 3435);
DISPLAY 0.659574 (-3290 3435);
PAINT MONO (-3290 3435);
DISPLAY INVISIBLE (-3290 3435);
FORCEPROP 1 LASTPIN (-3300 3425) BN 14
J 0
(-3312 3433);
DISPLAY 0.489362 (-3312 3433);
PAINT GREEN (-3312 3433);
FORCEPROP 2 LAST CDS_LIB mstr_standard
J 0
(-3250 3425);
DISPLAY 0.723404 (-3250 3425);
PAINT MONO (-3250 3425);
DISPLAY INVISIBLE (-3250 3425);
FORCEPROP 1 LAST BODY_TYPE PLUMBING
J 0
(-3250 3475);
DISPLAY 0.872340 (-3250 3475);
PAINT GREEN (-3250 3475);
DISPLAY INVISIBLE (-3250 3475);
FORCEPROP 1 LAST HDL_TAP TRUE
J 0
(-2925 3300);
DISPLAY 0.872340 (-2925 3300);
DISPLAY INVISIBLE (-2925 3300);
FORCEPROP 1 LAST PATH I210
J 0
(-3252 3425);
DISPLAY 0.872340 (-3252 3425);
PAINT GREEN (-3252 3425);
DISPLAY INVISIBLE (-3252 3425);
FORCEADD TAP..1
(-3250 3275);
FORCEPROP 3 LASTPIN (-3300 3275) SIG_NAME M_I_CPU0_SB_DQ<16>
J 0
(-3290 3285);
DISPLAY 0.659574 (-3290 3285);
PAINT MONO (-3290 3285);
DISPLAY INVISIBLE (-3290 3285);
FORCEPROP 1 LASTPIN (-3300 3275) BN 16
J 0
(-3312 3283);
DISPLAY 0.489362 (-3312 3283);
PAINT GREEN (-3312 3283);
FORCEPROP 2 LAST CDS_LIB mstr_standard
J 0
(-3250 3275);
DISPLAY 0.723404 (-3250 3275);
PAINT MONO (-3250 3275);
DISPLAY INVISIBLE (-3250 3275);
FORCEPROP 1 LAST BODY_TYPE PLUMBING
J 0
(-3250 3325);
DISPLAY 0.872340 (-3250 3325);
PAINT GREEN (-3250 3325);
DISPLAY INVISIBLE (-3250 3325);
FORCEPROP 1 LAST HDL_TAP TRUE
J 0
(-2925 3150);
DISPLAY 0.872340 (-2925 3150);
DISPLAY INVISIBLE (-2925 3150);
FORCEPROP 1 LAST PATH I211
J 0
(-3252 3275);
DISPLAY 0.872340 (-3252 3275);
PAINT GREEN (-3252 3275);
DISPLAY INVISIBLE (-3252 3275);
FORCEADD TAP..1
(-3250 3225);
FORCEPROP 3 LASTPIN (-3300 3225) SIG_NAME M_I_CPU0_SB_DQ<17>
J 0
(-3290 3235);
DISPLAY 0.659574 (-3290 3235);
PAINT MONO (-3290 3235);
DISPLAY INVISIBLE (-3290 3235);
FORCEPROP 1 LASTPIN (-3300 3225) BN 17
J 0
(-3312 3233);
DISPLAY 0.489362 (-3312 3233);
PAINT GREEN (-3312 3233);
FORCEPROP 2 LAST CDS_LIB mstr_standard
J 0
(-3250 3225);
DISPLAY 0.723404 (-3250 3225);
PAINT MONO (-3250 3225);
DISPLAY INVISIBLE (-3250 3225);
FORCEPROP 1 LAST BODY_TYPE PLUMBING
J 0
(-3250 3275);
DISPLAY 0.872340 (-3250 3275);
PAINT GREEN (-3250 3275);
DISPLAY INVISIBLE (-3250 3275);
FORCEPROP 1 LAST HDL_TAP TRUE
J 0
(-2925 3100);
DISPLAY 0.872340 (-2925 3100);
DISPLAY INVISIBLE (-2925 3100);
FORCEPROP 1 LAST PATH I212
J 0
(-3252 3225);
DISPLAY 0.872340 (-3252 3225);
PAINT GREEN (-3252 3225);
DISPLAY INVISIBLE (-3252 3225);
FORCEADD TAP..1
(-3250 3175);
FORCEPROP 3 LASTPIN (-3300 3175) SIG_NAME M_I_CPU0_SB_DQ<18>
J 0
(-3290 3185);
DISPLAY 0.659574 (-3290 3185);
PAINT MONO (-3290 3185);
DISPLAY INVISIBLE (-3290 3185);
FORCEPROP 1 LASTPIN (-3300 3175) BN 18
J 0
(-3312 3183);
DISPLAY 0.489362 (-3312 3183);
PAINT GREEN (-3312 3183);
FORCEPROP 2 LAST CDS_LIB mstr_standard
J 0
(-3250 3175);
DISPLAY 0.723404 (-3250 3175);
PAINT MONO (-3250 3175);
DISPLAY INVISIBLE (-3250 3175);
FORCEPROP 1 LAST BODY_TYPE PLUMBING
J 0
(-3250 3225);
DISPLAY 0.872340 (-3250 3225);
PAINT GREEN (-3250 3225);
DISPLAY INVISIBLE (-3250 3225);
FORCEPROP 1 LAST HDL_TAP TRUE
J 0
(-2925 3050);
DISPLAY 0.872340 (-2925 3050);
DISPLAY INVISIBLE (-2925 3050);
FORCEPROP 1 LAST PATH I213
J 0
(-3252 3175);
DISPLAY 0.872340 (-3252 3175);
PAINT GREEN (-3252 3175);
DISPLAY INVISIBLE (-3252 3175);
FORCEADD TAP..1
(-3250 3125);
FORCEPROP 3 LASTPIN (-3300 3125) SIG_NAME M_I_CPU0_SB_DQ<19>
J 0
(-3290 3135);
DISPLAY 0.659574 (-3290 3135);
PAINT MONO (-3290 3135);
DISPLAY INVISIBLE (-3290 3135);
FORCEPROP 1 LASTPIN (-3300 3125) BN 19
J 0
(-3312 3133);
DISPLAY 0.489362 (-3312 3133);
PAINT GREEN (-3312 3133);
FORCEPROP 2 LAST CDS_LIB mstr_standard
J 0
(-3250 3125);
DISPLAY 0.723404 (-3250 3125);
PAINT MONO (-3250 3125);
DISPLAY INVISIBLE (-3250 3125);
FORCEPROP 1 LAST BODY_TYPE PLUMBING
J 0
(-3250 3175);
DISPLAY 0.872340 (-3250 3175);
PAINT GREEN (-3250 3175);
DISPLAY INVISIBLE (-3250 3175);
FORCEPROP 1 LAST HDL_TAP TRUE
J 0
(-2925 3000);
DISPLAY 0.872340 (-2925 3000);
DISPLAY INVISIBLE (-2925 3000);
FORCEPROP 1 LAST PATH I214
J 0
(-3252 3125);
DISPLAY 0.872340 (-3252 3125);
PAINT GREEN (-3252 3125);
DISPLAY INVISIBLE (-3252 3125);
FORCEADD TAP..1
(-3250 3075);
FORCEPROP 3 LASTPIN (-3300 3075) SIG_NAME M_I_CPU0_SB_DQ<20>
J 0
(-3290 3085);
DISPLAY 0.659574 (-3290 3085);
PAINT MONO (-3290 3085);
DISPLAY INVISIBLE (-3290 3085);
FORCEPROP 1 LASTPIN (-3300 3075) BN 20
J 0
(-3312 3083);
DISPLAY 0.489362 (-3312 3083);
PAINT GREEN (-3312 3083);
FORCEPROP 2 LAST CDS_LIB mstr_standard
J 0
(-3250 3075);
DISPLAY 0.723404 (-3250 3075);
PAINT MONO (-3250 3075);
DISPLAY INVISIBLE (-3250 3075);
FORCEPROP 1 LAST BODY_TYPE PLUMBING
J 0
(-3250 3125);
DISPLAY 0.872340 (-3250 3125);
PAINT GREEN (-3250 3125);
DISPLAY INVISIBLE (-3250 3125);
FORCEPROP 1 LAST HDL_TAP TRUE
J 0
(-2925 2950);
DISPLAY 0.872340 (-2925 2950);
DISPLAY INVISIBLE (-2925 2950);
FORCEPROP 1 LAST PATH I215
J 0
(-3252 3075);
DISPLAY 0.872340 (-3252 3075);
PAINT GREEN (-3252 3075);
DISPLAY INVISIBLE (-3252 3075);
FORCEADD TAP..1
(-3250 2975);
FORCEPROP 3 LASTPIN (-3300 2975) SIG_NAME M_I_CPU0_SB_DQ<22>
J 0
(-3290 2985);
DISPLAY 0.659574 (-3290 2985);
PAINT MONO (-3290 2985);
DISPLAY INVISIBLE (-3290 2985);
FORCEPROP 1 LASTPIN (-3300 2975) BN 22
J 0
(-3312 2983);
DISPLAY 0.489362 (-3312 2983);
PAINT GREEN (-3312 2983);
FORCEPROP 2 LAST CDS_LIB mstr_standard
J 0
(-3250 2975);
DISPLAY 0.723404 (-3250 2975);
PAINT MONO (-3250 2975);
DISPLAY INVISIBLE (-3250 2975);
FORCEPROP 1 LAST BODY_TYPE PLUMBING
J 0
(-3250 3025);
DISPLAY 0.872340 (-3250 3025);
PAINT GREEN (-3250 3025);
DISPLAY INVISIBLE (-3250 3025);
FORCEPROP 1 LAST HDL_TAP TRUE
J 0
(-2925 2850);
DISPLAY 0.872340 (-2925 2850);
DISPLAY INVISIBLE (-2925 2850);
FORCEPROP 1 LAST PATH I216
J 0
(-3252 2975);
DISPLAY 0.872340 (-3252 2975);
PAINT GREEN (-3252 2975);
DISPLAY INVISIBLE (-3252 2975);
FORCEADD TAP..1
(-3250 3025);
FORCEPROP 3 LASTPIN (-3300 3025) SIG_NAME M_I_CPU0_SB_DQ<21>
J 0
(-3290 3035);
DISPLAY 0.659574 (-3290 3035);
PAINT MONO (-3290 3035);
DISPLAY INVISIBLE (-3290 3035);
FORCEPROP 1 LASTPIN (-3300 3025) BN 21
J 0
(-3312 3033);
DISPLAY 0.489362 (-3312 3033);
PAINT GREEN (-3312 3033);
FORCEPROP 2 LAST CDS_LIB mstr_standard
J 0
(-3250 3025);
DISPLAY 0.723404 (-3250 3025);
PAINT MONO (-3250 3025);
DISPLAY INVISIBLE (-3250 3025);
FORCEPROP 1 LAST BODY_TYPE PLUMBING
J 0
(-3250 3075);
DISPLAY 0.872340 (-3250 3075);
PAINT GREEN (-3250 3075);
DISPLAY INVISIBLE (-3250 3075);
FORCEPROP 1 LAST HDL_TAP TRUE
J 0
(-2925 2900);
DISPLAY 0.872340 (-2925 2900);
DISPLAY INVISIBLE (-2925 2900);
FORCEPROP 1 LAST PATH I217
J 0
(-3252 3025);
DISPLAY 0.872340 (-3252 3025);
PAINT GREEN (-3252 3025);
DISPLAY INVISIBLE (-3252 3025);
FORCEADD TAP..1
(-3250 2925);
FORCEPROP 3 LASTPIN (-3300 2925) SIG_NAME M_I_CPU0_SB_DQ<23>
J 0
(-3290 2935);
DISPLAY 0.659574 (-3290 2935);
PAINT MONO (-3290 2935);
DISPLAY INVISIBLE (-3290 2935);
FORCEPROP 1 LASTPIN (-3300 2925) BN 23
J 0
(-3312 2933);
DISPLAY 0.489362 (-3312 2933);
PAINT GREEN (-3312 2933);
FORCEPROP 2 LAST CDS_LIB mstr_standard
J 0
(-3250 2925);
DISPLAY 0.723404 (-3250 2925);
PAINT MONO (-3250 2925);
DISPLAY INVISIBLE (-3250 2925);
FORCEPROP 1 LAST BODY_TYPE PLUMBING
J 0
(-3250 2975);
DISPLAY 0.872340 (-3250 2975);
PAINT GREEN (-3250 2975);
DISPLAY INVISIBLE (-3250 2975);
FORCEPROP 1 LAST HDL_TAP TRUE
J 0
(-2925 2800);
DISPLAY 0.872340 (-2925 2800);
DISPLAY INVISIBLE (-2925 2800);
FORCEPROP 1 LAST PATH I218
J 0
(-3252 2925);
DISPLAY 0.872340 (-3252 2925);
PAINT GREEN (-3252 2925);
DISPLAY INVISIBLE (-3252 2925);
FORCEADD TAP..1
(-3250 2825);
FORCEPROP 3 LASTPIN (-3300 2825) SIG_NAME M_I_CPU0_SB_DQ<24>
J 0
(-3290 2835);
DISPLAY 0.659574 (-3290 2835);
PAINT MONO (-3290 2835);
DISPLAY INVISIBLE (-3290 2835);
FORCEPROP 1 LASTPIN (-3300 2825) BN 24
J 0
(-3312 2833);
DISPLAY 0.489362 (-3312 2833);
PAINT GREEN (-3312 2833);
FORCEPROP 2 LAST CDS_LIB mstr_standard
J 0
(-3250 2825);
DISPLAY 0.723404 (-3250 2825);
PAINT MONO (-3250 2825);
DISPLAY INVISIBLE (-3250 2825);
FORCEPROP 1 LAST BODY_TYPE PLUMBING
J 0
(-3250 2875);
DISPLAY 0.872340 (-3250 2875);
PAINT GREEN (-3250 2875);
DISPLAY INVISIBLE (-3250 2875);
FORCEPROP 1 LAST HDL_TAP TRUE
J 0
(-2925 2700);
DISPLAY 0.872340 (-2925 2700);
DISPLAY INVISIBLE (-2925 2700);
FORCEPROP 1 LAST PATH I219
J 0
(-3252 2825);
DISPLAY 0.872340 (-3252 2825);
PAINT GREEN (-3252 2825);
DISPLAY INVISIBLE (-3252 2825);
FORCEADD TAP..1
(-3250 2775);
FORCEPROP 3 LASTPIN (-3300 2775) SIG_NAME M_I_CPU0_SB_DQ<25>
J 0
(-3290 2785);
DISPLAY 0.659574 (-3290 2785);
PAINT MONO (-3290 2785);
DISPLAY INVISIBLE (-3290 2785);
FORCEPROP 1 LASTPIN (-3300 2775) BN 25
J 0
(-3312 2783);
DISPLAY 0.489362 (-3312 2783);
PAINT GREEN (-3312 2783);
FORCEPROP 2 LAST CDS_LIB mstr_standard
J 0
(-3250 2775);
DISPLAY 0.723404 (-3250 2775);
PAINT MONO (-3250 2775);
DISPLAY INVISIBLE (-3250 2775);
FORCEPROP 1 LAST BODY_TYPE PLUMBING
J 0
(-3250 2825);
DISPLAY 0.872340 (-3250 2825);
PAINT GREEN (-3250 2825);
DISPLAY INVISIBLE (-3250 2825);
FORCEPROP 1 LAST HDL_TAP TRUE
J 0
(-2925 2650);
DISPLAY 0.872340 (-2925 2650);
DISPLAY INVISIBLE (-2925 2650);
FORCEPROP 1 LAST PATH I220
J 0
(-3252 2775);
DISPLAY 0.872340 (-3252 2775);
PAINT GREEN (-3252 2775);
DISPLAY INVISIBLE (-3252 2775);
FORCEADD TAP..1
(-3250 2725);
FORCEPROP 3 LASTPIN (-3300 2725) SIG_NAME M_I_CPU0_SB_DQ<26>
J 0
(-3290 2735);
DISPLAY 0.659574 (-3290 2735);
PAINT MONO (-3290 2735);
DISPLAY INVISIBLE (-3290 2735);
FORCEPROP 1 LASTPIN (-3300 2725) BN 26
J 0
(-3312 2733);
DISPLAY 0.489362 (-3312 2733);
PAINT GREEN (-3312 2733);
FORCEPROP 2 LAST CDS_LIB mstr_standard
J 0
(-3250 2725);
DISPLAY 0.723404 (-3250 2725);
PAINT MONO (-3250 2725);
DISPLAY INVISIBLE (-3250 2725);
FORCEPROP 1 LAST BODY_TYPE PLUMBING
J 0
(-3250 2775);
DISPLAY 0.872340 (-3250 2775);
PAINT GREEN (-3250 2775);
DISPLAY INVISIBLE (-3250 2775);
FORCEPROP 1 LAST HDL_TAP TRUE
J 0
(-2925 2600);
DISPLAY 0.872340 (-2925 2600);
DISPLAY INVISIBLE (-2925 2600);
FORCEPROP 1 LAST PATH I221
J 0
(-3252 2725);
DISPLAY 0.872340 (-3252 2725);
PAINT GREEN (-3252 2725);
DISPLAY INVISIBLE (-3252 2725);
FORCEADD TAP..1
(-3250 2575);
FORCEPROP 3 LASTPIN (-3300 2575) SIG_NAME M_I_CPU0_SB_DQ<29>
J 0
(-3290 2585);
DISPLAY 0.659574 (-3290 2585);
PAINT MONO (-3290 2585);
DISPLAY INVISIBLE (-3290 2585);
FORCEPROP 1 LASTPIN (-3300 2575) BN 29
J 0
(-3312 2583);
DISPLAY 0.489362 (-3312 2583);
PAINT GREEN (-3312 2583);
FORCEPROP 2 LAST CDS_LIB mstr_standard
J 0
(-3250 2575);
DISPLAY 0.723404 (-3250 2575);
PAINT MONO (-3250 2575);
DISPLAY INVISIBLE (-3250 2575);
FORCEPROP 1 LAST BODY_TYPE PLUMBING
J 0
(-3250 2625);
DISPLAY 0.872340 (-3250 2625);
PAINT GREEN (-3250 2625);
DISPLAY INVISIBLE (-3250 2625);
FORCEPROP 1 LAST HDL_TAP TRUE
J 0
(-2925 2450);
DISPLAY 0.872340 (-2925 2450);
DISPLAY INVISIBLE (-2925 2450);
FORCEPROP 1 LAST PATH I222
J 0
(-3252 2575);
DISPLAY 0.872340 (-3252 2575);
PAINT GREEN (-3252 2575);
DISPLAY INVISIBLE (-3252 2575);
FORCEADD TAP..1
(-3250 2625);
FORCEPROP 3 LASTPIN (-3300 2625) SIG_NAME M_I_CPU0_SB_DQ<28>
J 0
(-3290 2635);
DISPLAY 0.659574 (-3290 2635);
PAINT MONO (-3290 2635);
DISPLAY INVISIBLE (-3290 2635);
FORCEPROP 1 LASTPIN (-3300 2625) BN 28
J 0
(-3312 2633);
DISPLAY 0.489362 (-3312 2633);
PAINT GREEN (-3312 2633);
FORCEPROP 2 LAST CDS_LIB mstr_standard
J 0
(-3250 2625);
DISPLAY 0.723404 (-3250 2625);
PAINT MONO (-3250 2625);
DISPLAY INVISIBLE (-3250 2625);
FORCEPROP 1 LAST BODY_TYPE PLUMBING
J 0
(-3250 2675);
DISPLAY 0.872340 (-3250 2675);
PAINT GREEN (-3250 2675);
DISPLAY INVISIBLE (-3250 2675);
FORCEPROP 1 LAST HDL_TAP TRUE
J 0
(-2925 2500);
DISPLAY 0.872340 (-2925 2500);
DISPLAY INVISIBLE (-2925 2500);
FORCEPROP 1 LAST PATH I223
J 0
(-3252 2625);
DISPLAY 0.872340 (-3252 2625);
PAINT GREEN (-3252 2625);
DISPLAY INVISIBLE (-3252 2625);
FORCEADD TAP..1
(-3250 2675);
FORCEPROP 3 LASTPIN (-3300 2675) SIG_NAME M_I_CPU0_SB_DQ<27>
J 0
(-3290 2685);
DISPLAY 0.659574 (-3290 2685);
PAINT MONO (-3290 2685);
DISPLAY INVISIBLE (-3290 2685);
FORCEPROP 1 LASTPIN (-3300 2675) BN 27
J 0
(-3312 2683);
DISPLAY 0.489362 (-3312 2683);
PAINT GREEN (-3312 2683);
FORCEPROP 2 LAST CDS_LIB mstr_standard
J 0
(-3250 2675);
DISPLAY 0.723404 (-3250 2675);
PAINT MONO (-3250 2675);
DISPLAY INVISIBLE (-3250 2675);
FORCEPROP 1 LAST BODY_TYPE PLUMBING
J 0
(-3250 2725);
DISPLAY 0.872340 (-3250 2725);
PAINT GREEN (-3250 2725);
DISPLAY INVISIBLE (-3250 2725);
FORCEPROP 1 LAST HDL_TAP TRUE
J 0
(-2925 2550);
DISPLAY 0.872340 (-2925 2550);
DISPLAY INVISIBLE (-2925 2550);
FORCEPROP 1 LAST PATH I224
J 0
(-3252 2675);
DISPLAY 0.872340 (-3252 2675);
PAINT GREEN (-3252 2675);
DISPLAY INVISIBLE (-3252 2675);
FORCEADD TAP..1
(-3250 2525);
FORCEPROP 3 LASTPIN (-3300 2525) SIG_NAME M_I_CPU0_SB_DQ<30>
J 0
(-3290 2535);
DISPLAY 0.659574 (-3290 2535);
PAINT MONO (-3290 2535);
DISPLAY INVISIBLE (-3290 2535);
FORCEPROP 1 LASTPIN (-3300 2525) BN 30
J 0
(-3312 2533);
DISPLAY 0.489362 (-3312 2533);
PAINT GREEN (-3312 2533);
FORCEPROP 2 LAST CDS_LIB mstr_standard
J 0
(-3250 2525);
DISPLAY 0.723404 (-3250 2525);
PAINT MONO (-3250 2525);
DISPLAY INVISIBLE (-3250 2525);
FORCEPROP 1 LAST BODY_TYPE PLUMBING
J 0
(-3250 2575);
DISPLAY 0.872340 (-3250 2575);
PAINT GREEN (-3250 2575);
DISPLAY INVISIBLE (-3250 2575);
FORCEPROP 1 LAST HDL_TAP TRUE
J 0
(-2925 2400);
DISPLAY 0.872340 (-2925 2400);
DISPLAY INVISIBLE (-2925 2400);
FORCEPROP 1 LAST PATH I225
J 0
(-3252 2525);
DISPLAY 0.872340 (-3252 2525);
PAINT GREEN (-3252 2525);
DISPLAY INVISIBLE (-3252 2525);
FORCEADD TAP..1
(-3250 2475);
FORCEPROP 3 LASTPIN (-3300 2475) SIG_NAME M_I_CPU0_SB_DQ<31>
J 0
(-3290 2485);
DISPLAY 0.659574 (-3290 2485);
PAINT MONO (-3290 2485);
DISPLAY INVISIBLE (-3290 2485);
FORCEPROP 1 LASTPIN (-3300 2475) BN 31
J 0
(-3312 2483);
DISPLAY 0.489362 (-3312 2483);
PAINT GREEN (-3312 2483);
FORCEPROP 2 LAST CDS_LIB mstr_standard
J 0
(-3250 2475);
DISPLAY 0.723404 (-3250 2475);
PAINT MONO (-3250 2475);
DISPLAY INVISIBLE (-3250 2475);
FORCEPROP 1 LAST BODY_TYPE PLUMBING
J 0
(-3250 2525);
DISPLAY 0.872340 (-3250 2525);
PAINT GREEN (-3250 2525);
DISPLAY INVISIBLE (-3250 2525);
FORCEPROP 1 LAST HDL_TAP TRUE
J 0
(-2925 2350);
DISPLAY 0.872340 (-2925 2350);
DISPLAY INVISIBLE (-2925 2350);
FORCEPROP 1 LAST PATH I226
J 0
(-3252 2475);
DISPLAY 0.872340 (-3252 2475);
PAINT GREEN (-3252 2475);
DISPLAY INVISIBLE (-3252 2475);
FORCEADD TAP..1
(-3250 2325);
FORCEPROP 3 LASTPIN (-3300 2325) SIG_NAME M_I_CPU0_SA_CB<1>
J 0
(-3290 2335);
DISPLAY 0.659574 (-3290 2335);
PAINT MONO (-3290 2335);
DISPLAY INVISIBLE (-3290 2335);
FORCEPROP 1 LASTPIN (-3300 2325) BN 1
J 0
(-3312 2333);
DISPLAY 0.489362 (-3312 2333);
PAINT GREEN (-3312 2333);
FORCEPROP 2 LAST CDS_LIB mstr_standard
J 2
(-3250 2325);
DISPLAY 0.723404 (-3250 2325);
PAINT MONO (-3250 2325);
DISPLAY INVISIBLE (-3250 2325);
FORCEPROP 1 LAST BODY_TYPE PLUMBING
J 0
(-3250 2375);
DISPLAY 0.872340 (-3250 2375);
PAINT GREEN (-3250 2375);
DISPLAY INVISIBLE (-3250 2375);
FORCEPROP 1 LAST HDL_TAP TRUE
J 0
(-2925 2200);
DISPLAY 0.872340 (-2925 2200);
DISPLAY INVISIBLE (-2925 2200);
FORCEPROP 1 LAST PATH I227
J 0
(-3252 2325);
DISPLAY 0.872340 (-3252 2325);
PAINT GREEN (-3252 2325);
DISPLAY INVISIBLE (-3252 2325);
FORCEADD TAP..1
(-3250 2375);
FORCEPROP 3 LASTPIN (-3300 2375) SIG_NAME M_I_CPU0_SA_CB<0>
J 0
(-3290 2385);
DISPLAY 0.659574 (-3290 2385);
PAINT MONO (-3290 2385);
DISPLAY INVISIBLE (-3290 2385);
FORCEPROP 1 LASTPIN (-3300 2375) BN 0
J 0
(-3312 2383);
DISPLAY 0.489362 (-3312 2383);
PAINT GREEN (-3312 2383);
FORCEPROP 2 LAST CDS_LIB mstr_standard
J 2
(-3250 2375);
DISPLAY 0.723404 (-3250 2375);
PAINT MONO (-3250 2375);
DISPLAY INVISIBLE (-3250 2375);
FORCEPROP 1 LAST BODY_TYPE PLUMBING
J 0
(-3250 2425);
DISPLAY 0.872340 (-3250 2425);
PAINT GREEN (-3250 2425);
DISPLAY INVISIBLE (-3250 2425);
FORCEPROP 1 LAST HDL_TAP TRUE
J 0
(-2925 2250);
DISPLAY 0.872340 (-2925 2250);
DISPLAY INVISIBLE (-2925 2250);
FORCEPROP 1 LAST PATH I228
J 0
(-3252 2375);
DISPLAY 0.872340 (-3252 2375);
PAINT GREEN (-3252 2375);
DISPLAY INVISIBLE (-3252 2375);
FORCEADD TAP..1
(-3250 2225);
FORCEPROP 3 LASTPIN (-3300 2225) SIG_NAME M_I_CPU0_SA_CB<3>
J 0
(-3290 2235);
DISPLAY 0.659574 (-3290 2235);
PAINT MONO (-3290 2235);
DISPLAY INVISIBLE (-3290 2235);
FORCEPROP 1 LASTPIN (-3300 2225) BN 3
J 0
(-3312 2233);
DISPLAY 0.489362 (-3312 2233);
PAINT GREEN (-3312 2233);
FORCEPROP 2 LAST CDS_LIB mstr_standard
J 2
(-3250 2225);
DISPLAY 0.723404 (-3250 2225);
PAINT MONO (-3250 2225);
DISPLAY INVISIBLE (-3250 2225);
FORCEPROP 1 LAST BODY_TYPE PLUMBING
J 0
(-3250 2275);
DISPLAY 0.872340 (-3250 2275);
PAINT GREEN (-3250 2275);
DISPLAY INVISIBLE (-3250 2275);
FORCEPROP 1 LAST HDL_TAP TRUE
J 0
(-2925 2100);
DISPLAY 0.872340 (-2925 2100);
DISPLAY INVISIBLE (-2925 2100);
FORCEPROP 1 LAST PATH I229
J 0
(-3252 2225);
DISPLAY 0.872340 (-3252 2225);
PAINT GREEN (-3252 2225);
DISPLAY INVISIBLE (-3252 2225);
FORCEADD TAP..1
(-3250 2275);
FORCEPROP 3 LASTPIN (-3300 2275) SIG_NAME M_I_CPU0_SA_CB<2>
J 0
(-3290 2285);
DISPLAY 0.659574 (-3290 2285);
PAINT MONO (-3290 2285);
DISPLAY INVISIBLE (-3290 2285);
FORCEPROP 1 LASTPIN (-3300 2275) BN 2
J 0
(-3312 2283);
DISPLAY 0.489362 (-3312 2283);
PAINT GREEN (-3312 2283);
FORCEPROP 2 LAST CDS_LIB mstr_standard
J 2
(-3250 2275);
DISPLAY 0.723404 (-3250 2275);
PAINT MONO (-3250 2275);
DISPLAY INVISIBLE (-3250 2275);
FORCEPROP 1 LAST BODY_TYPE PLUMBING
J 0
(-3250 2325);
DISPLAY 0.872340 (-3250 2325);
PAINT GREEN (-3250 2325);
DISPLAY INVISIBLE (-3250 2325);
FORCEPROP 1 LAST HDL_TAP TRUE
J 0
(-2925 2150);
DISPLAY 0.872340 (-2925 2150);
DISPLAY INVISIBLE (-2925 2150);
FORCEPROP 1 LAST PATH I230
J 0
(-3252 2275);
DISPLAY 0.872340 (-3252 2275);
PAINT GREEN (-3252 2275);
DISPLAY INVISIBLE (-3252 2275);
FORCEADD TAP..1
(-3250 2075);
FORCEPROP 3 LASTPIN (-3300 2075) SIG_NAME M_I_CPU0_SA_CB<6>
J 0
(-3290 2085);
DISPLAY 0.659574 (-3290 2085);
PAINT MONO (-3290 2085);
DISPLAY INVISIBLE (-3290 2085);
FORCEPROP 1 LASTPIN (-3300 2075) BN 6
J 0
(-3312 2083);
DISPLAY 0.489362 (-3312 2083);
PAINT GREEN (-3312 2083);
FORCEPROP 2 LAST CDS_LIB mstr_standard
J 2
(-3250 2075);
DISPLAY 0.723404 (-3250 2075);
PAINT MONO (-3250 2075);
DISPLAY INVISIBLE (-3250 2075);
FORCEPROP 1 LAST BODY_TYPE PLUMBING
J 0
(-3250 2125);
DISPLAY 0.872340 (-3250 2125);
PAINT GREEN (-3250 2125);
DISPLAY INVISIBLE (-3250 2125);
FORCEPROP 1 LAST HDL_TAP TRUE
J 0
(-2925 1950);
DISPLAY 0.872340 (-2925 1950);
DISPLAY INVISIBLE (-2925 1950);
FORCEPROP 1 LAST PATH I231
J 0
(-3252 2075);
DISPLAY 0.872340 (-3252 2075);
PAINT GREEN (-3252 2075);
DISPLAY INVISIBLE (-3252 2075);
FORCEADD TAP..1
(-3250 2125);
FORCEPROP 3 LASTPIN (-3300 2125) SIG_NAME M_I_CPU0_SA_CB<5>
J 0
(-3290 2135);
DISPLAY 0.659574 (-3290 2135);
PAINT MONO (-3290 2135);
DISPLAY INVISIBLE (-3290 2135);
FORCEPROP 1 LASTPIN (-3300 2125) BN 5
J 0
(-3312 2133);
DISPLAY 0.489362 (-3312 2133);
PAINT GREEN (-3312 2133);
FORCEPROP 2 LAST CDS_LIB mstr_standard
J 2
(-3250 2125);
DISPLAY 0.723404 (-3250 2125);
PAINT MONO (-3250 2125);
DISPLAY INVISIBLE (-3250 2125);
FORCEPROP 1 LAST BODY_TYPE PLUMBING
J 0
(-3250 2175);
DISPLAY 0.872340 (-3250 2175);
PAINT GREEN (-3250 2175);
DISPLAY INVISIBLE (-3250 2175);
FORCEPROP 1 LAST HDL_TAP TRUE
J 0
(-2925 2000);
DISPLAY 0.872340 (-2925 2000);
DISPLAY INVISIBLE (-2925 2000);
FORCEPROP 1 LAST PATH I232
J 0
(-3252 2125);
DISPLAY 0.872340 (-3252 2125);
PAINT GREEN (-3252 2125);
DISPLAY INVISIBLE (-3252 2125);
FORCEADD TAP..1
(-3250 2175);
FORCEPROP 3 LASTPIN (-3300 2175) SIG_NAME M_I_CPU0_SA_CB<4>
J 0
(-3290 2185);
DISPLAY 0.659574 (-3290 2185);
PAINT MONO (-3290 2185);
DISPLAY INVISIBLE (-3290 2185);
FORCEPROP 1 LASTPIN (-3300 2175) BN 4
J 0
(-3312 2183);
DISPLAY 0.489362 (-3312 2183);
PAINT GREEN (-3312 2183);
FORCEPROP 2 LAST CDS_LIB mstr_standard
J 2
(-3250 2175);
DISPLAY 0.723404 (-3250 2175);
PAINT MONO (-3250 2175);
DISPLAY INVISIBLE (-3250 2175);
FORCEPROP 1 LAST BODY_TYPE PLUMBING
J 0
(-3250 2225);
DISPLAY 0.872340 (-3250 2225);
PAINT GREEN (-3250 2225);
DISPLAY INVISIBLE (-3250 2225);
FORCEPROP 1 LAST HDL_TAP TRUE
J 0
(-2925 2050);
DISPLAY 0.872340 (-2925 2050);
DISPLAY INVISIBLE (-2925 2050);
FORCEPROP 1 LAST PATH I233
J 0
(-3252 2175);
DISPLAY 0.872340 (-3252 2175);
PAINT GREEN (-3252 2175);
DISPLAY INVISIBLE (-3252 2175);
FORCEADD OFFPAGE..6
R 2
(-2650 1975);
FORCEPROP 2 LAST $XR0 93 
J 0
(-2436 1975);
DISPLAY 0.638298 (-2436 1975);
PAINT MONO (-2436 1975);
FORCEPROP 2 LAST PATH I234
J 0
(-2425 2025);
DISPLAY 1.021277 (-2425 2025);
DISPLAY INVISIBLE (-2425 2025);
FORCEPROP 1 LAST COMMENT_BODY TRUE
J 2
(-2750 1900);
DISPLAY 0.872340 (-2750 1900);
PAINT GREEN (-2750 1900);
DISPLAY INVISIBLE (-2750 1900);
FORCEPROP 1 LAST OFFPAGE TRUE
J 2
(-2975 1850);
DISPLAY 0.872340 (-2975 1850);
PAINT GREEN (-2975 1850);
DISPLAY INVISIBLE (-2975 1850);
FORCEPROP 2 LAST CDS_LIB mstr_standard
J 2
(-2650 1975);
DISPLAY 0.723404 (-2650 1975);
PAINT MONO (-2650 1975);
DISPLAY INVISIBLE (-2650 1975);
FORCEADD TAP..1
(-3250 1925);
FORCEPROP 3 LASTPIN (-3300 1925) SIG_NAME M_I_CPU0_SB_CB<0>
J 0
(-3290 1935);
DISPLAY 0.659574 (-3290 1935);
PAINT MONO (-3290 1935);
DISPLAY INVISIBLE (-3290 1935);
FORCEPROP 1 LASTPIN (-3300 1925) BN 0
J 0
(-3312 1933);
DISPLAY 0.489362 (-3312 1933);
PAINT GREEN (-3312 1933);
FORCEPROP 2 LAST CDS_LIB mstr_standard
J 2
(-3250 1925);
DISPLAY 0.723404 (-3250 1925);
PAINT MONO (-3250 1925);
DISPLAY INVISIBLE (-3250 1925);
FORCEPROP 1 LAST BODY_TYPE PLUMBING
J 0
(-3250 1975);
DISPLAY 0.872340 (-3250 1975);
PAINT GREEN (-3250 1975);
DISPLAY INVISIBLE (-3250 1975);
FORCEPROP 1 LAST HDL_TAP TRUE
J 0
(-2925 1800);
DISPLAY 0.872340 (-2925 1800);
DISPLAY INVISIBLE (-2925 1800);
FORCEPROP 1 LAST PATH I235
J 0
(-3252 1925);
DISPLAY 0.872340 (-3252 1925);
PAINT GREEN (-3252 1925);
DISPLAY INVISIBLE (-3252 1925);
FORCEADD TAP..1
(-3250 2025);
FORCEPROP 3 LASTPIN (-3300 2025) SIG_NAME M_I_CPU0_SA_CB<7>
J 0
(-3290 2035);
DISPLAY 0.659574 (-3290 2035);
PAINT MONO (-3290 2035);
DISPLAY INVISIBLE (-3290 2035);
FORCEPROP 1 LASTPIN (-3300 2025) BN 7
J 0
(-3312 2033);
DISPLAY 0.489362 (-3312 2033);
PAINT GREEN (-3312 2033);
FORCEPROP 2 LAST CDS_LIB mstr_standard
J 2
(-3250 2025);
DISPLAY 0.723404 (-3250 2025);
PAINT MONO (-3250 2025);
DISPLAY INVISIBLE (-3250 2025);
FORCEPROP 1 LAST BODY_TYPE PLUMBING
J 0
(-3250 2075);
DISPLAY 0.872340 (-3250 2075);
PAINT GREEN (-3250 2075);
DISPLAY INVISIBLE (-3250 2075);
FORCEPROP 1 LAST HDL_TAP TRUE
J 0
(-2925 1900);
DISPLAY 0.872340 (-2925 1900);
DISPLAY INVISIBLE (-2925 1900);
FORCEPROP 1 LAST PATH I236
J 0
(-3252 2025);
DISPLAY 0.872340 (-3252 2025);
PAINT GREEN (-3252 2025);
DISPLAY INVISIBLE (-3252 2025);
FORCEADD TAP..1
(-3250 1825);
FORCEPROP 3 LASTPIN (-3300 1825) SIG_NAME M_I_CPU0_SB_CB<2>
J 0
(-3290 1835);
DISPLAY 0.659574 (-3290 1835);
PAINT MONO (-3290 1835);
DISPLAY INVISIBLE (-3290 1835);
FORCEPROP 1 LASTPIN (-3300 1825) BN 2
J 0
(-3312 1833);
DISPLAY 0.489362 (-3312 1833);
PAINT GREEN (-3312 1833);
FORCEPROP 2 LAST CDS_LIB mstr_standard
J 2
(-3250 1825);
DISPLAY 0.723404 (-3250 1825);
PAINT MONO (-3250 1825);
DISPLAY INVISIBLE (-3250 1825);
FORCEPROP 1 LAST BODY_TYPE PLUMBING
J 0
(-3250 1875);
DISPLAY 0.872340 (-3250 1875);
PAINT GREEN (-3250 1875);
DISPLAY INVISIBLE (-3250 1875);
FORCEPROP 1 LAST HDL_TAP TRUE
J 0
(-2925 1700);
DISPLAY 0.872340 (-2925 1700);
DISPLAY INVISIBLE (-2925 1700);
FORCEPROP 1 LAST PATH I237
J 0
(-3252 1825);
DISPLAY 0.872340 (-3252 1825);
PAINT GREEN (-3252 1825);
DISPLAY INVISIBLE (-3252 1825);
FORCEADD TAP..1
(-3250 1875);
FORCEPROP 3 LASTPIN (-3300 1875) SIG_NAME M_I_CPU0_SB_CB<1>
J 0
(-3290 1885);
DISPLAY 0.659574 (-3290 1885);
PAINT MONO (-3290 1885);
DISPLAY INVISIBLE (-3290 1885);
FORCEPROP 1 LASTPIN (-3300 1875) BN 1
J 0
(-3312 1883);
DISPLAY 0.489362 (-3312 1883);
PAINT GREEN (-3312 1883);
FORCEPROP 2 LAST CDS_LIB mstr_standard
J 2
(-3250 1875);
DISPLAY 0.723404 (-3250 1875);
PAINT MONO (-3250 1875);
DISPLAY INVISIBLE (-3250 1875);
FORCEPROP 1 LAST BODY_TYPE PLUMBING
J 0
(-3250 1925);
DISPLAY 0.872340 (-3250 1925);
PAINT GREEN (-3250 1925);
DISPLAY INVISIBLE (-3250 1925);
FORCEPROP 1 LAST HDL_TAP TRUE
J 0
(-2925 1750);
DISPLAY 0.872340 (-2925 1750);
DISPLAY INVISIBLE (-2925 1750);
FORCEPROP 1 LAST PATH I238
J 0
(-3252 1875);
DISPLAY 0.872340 (-3252 1875);
PAINT GREEN (-3252 1875);
DISPLAY INVISIBLE (-3252 1875);
FORCEADD TAP..1
(-3250 1775);
FORCEPROP 3 LASTPIN (-3300 1775) SIG_NAME M_I_CPU0_SB_CB<3>
J 0
(-3290 1785);
DISPLAY 0.659574 (-3290 1785);
PAINT MONO (-3290 1785);
DISPLAY INVISIBLE (-3290 1785);
FORCEPROP 1 LASTPIN (-3300 1775) BN 3
J 0
(-3312 1783);
DISPLAY 0.489362 (-3312 1783);
PAINT GREEN (-3312 1783);
FORCEPROP 2 LAST CDS_LIB mstr_standard
J 2
(-3250 1775);
DISPLAY 0.723404 (-3250 1775);
PAINT MONO (-3250 1775);
DISPLAY INVISIBLE (-3250 1775);
FORCEPROP 1 LAST BODY_TYPE PLUMBING
J 0
(-3250 1825);
DISPLAY 0.872340 (-3250 1825);
PAINT GREEN (-3250 1825);
DISPLAY INVISIBLE (-3250 1825);
FORCEPROP 1 LAST HDL_TAP TRUE
J 0
(-2925 1650);
DISPLAY 0.872340 (-2925 1650);
DISPLAY INVISIBLE (-2925 1650);
FORCEPROP 1 LAST PATH I239
J 0
(-3252 1775);
DISPLAY 0.872340 (-3252 1775);
PAINT GREEN (-3252 1775);
DISPLAY INVISIBLE (-3252 1775);
FORCEADD TAP..1
(-3250 1725);
FORCEPROP 3 LASTPIN (-3300 1725) SIG_NAME M_I_CPU0_SB_CB<4>
J 0
(-3290 1735);
DISPLAY 0.659574 (-3290 1735);
PAINT MONO (-3290 1735);
DISPLAY INVISIBLE (-3290 1735);
FORCEPROP 1 LASTPIN (-3300 1725) BN 4
J 0
(-3312 1733);
DISPLAY 0.489362 (-3312 1733);
PAINT GREEN (-3312 1733);
FORCEPROP 2 LAST CDS_LIB mstr_standard
J 2
(-3250 1725);
DISPLAY 0.723404 (-3250 1725);
PAINT MONO (-3250 1725);
DISPLAY INVISIBLE (-3250 1725);
FORCEPROP 1 LAST BODY_TYPE PLUMBING
J 0
(-3250 1775);
DISPLAY 0.872340 (-3250 1775);
PAINT GREEN (-3250 1775);
DISPLAY INVISIBLE (-3250 1775);
FORCEPROP 1 LAST HDL_TAP TRUE
J 0
(-2925 1600);
DISPLAY 0.872340 (-2925 1600);
DISPLAY INVISIBLE (-2925 1600);
FORCEPROP 1 LAST PATH I240
J 0
(-3252 1725);
DISPLAY 0.872340 (-3252 1725);
PAINT GREEN (-3252 1725);
DISPLAY INVISIBLE (-3252 1725);
FORCEADD TAP..1
(-3250 1675);
FORCEPROP 3 LASTPIN (-3300 1675) SIG_NAME M_I_CPU0_SB_CB<5>
J 0
(-3290 1685);
DISPLAY 0.659574 (-3290 1685);
PAINT MONO (-3290 1685);
DISPLAY INVISIBLE (-3290 1685);
FORCEPROP 1 LASTPIN (-3300 1675) BN 5
J 0
(-3312 1683);
DISPLAY 0.489362 (-3312 1683);
PAINT GREEN (-3312 1683);
FORCEPROP 2 LAST CDS_LIB mstr_standard
J 2
(-3250 1675);
DISPLAY 0.723404 (-3250 1675);
PAINT MONO (-3250 1675);
DISPLAY INVISIBLE (-3250 1675);
FORCEPROP 1 LAST BODY_TYPE PLUMBING
J 0
(-3250 1725);
DISPLAY 0.872340 (-3250 1725);
PAINT GREEN (-3250 1725);
DISPLAY INVISIBLE (-3250 1725);
FORCEPROP 1 LAST HDL_TAP TRUE
J 0
(-2925 1550);
DISPLAY 0.872340 (-2925 1550);
DISPLAY INVISIBLE (-2925 1550);
FORCEPROP 1 LAST PATH I241
J 0
(-3252 1675);
DISPLAY 0.872340 (-3252 1675);
PAINT GREEN (-3252 1675);
DISPLAY INVISIBLE (-3252 1675);
FORCEADD TAP..1
(-3250 1575);
FORCEPROP 3 LASTPIN (-3300 1575) SIG_NAME M_I_CPU0_SB_CB<7>
J 0
(-3290 1585);
DISPLAY 0.659574 (-3290 1585);
PAINT MONO (-3290 1585);
DISPLAY INVISIBLE (-3290 1585);
FORCEPROP 1 LASTPIN (-3300 1575) BN 7
J 0
(-3312 1583);
DISPLAY 0.489362 (-3312 1583);
PAINT GREEN (-3312 1583);
FORCEPROP 2 LAST CDS_LIB mstr_standard
J 2
(-3250 1575);
DISPLAY 0.723404 (-3250 1575);
PAINT MONO (-3250 1575);
DISPLAY INVISIBLE (-3250 1575);
FORCEPROP 1 LAST BODY_TYPE PLUMBING
J 0
(-3250 1625);
DISPLAY 0.872340 (-3250 1625);
PAINT GREEN (-3250 1625);
DISPLAY INVISIBLE (-3250 1625);
FORCEPROP 1 LAST HDL_TAP TRUE
J 0
(-2925 1450);
DISPLAY 0.872340 (-2925 1450);
DISPLAY INVISIBLE (-2925 1450);
FORCEPROP 1 LAST PATH I242
J 0
(-3252 1575);
DISPLAY 0.872340 (-3252 1575);
PAINT GREEN (-3252 1575);
DISPLAY INVISIBLE (-3252 1575);
FORCEADD TAP..1
(-3250 1625);
FORCEPROP 3 LASTPIN (-3300 1625) SIG_NAME M_I_CPU0_SB_CB<6>
J 0
(-3290 1635);
DISPLAY 0.659574 (-3290 1635);
PAINT MONO (-3290 1635);
DISPLAY INVISIBLE (-3290 1635);
FORCEPROP 1 LASTPIN (-3300 1625) BN 6
J 0
(-3312 1633);
DISPLAY 0.489362 (-3312 1633);
PAINT GREEN (-3312 1633);
FORCEPROP 2 LAST CDS_LIB mstr_standard
J 2
(-3250 1625);
DISPLAY 0.723404 (-3250 1625);
PAINT MONO (-3250 1625);
DISPLAY INVISIBLE (-3250 1625);
FORCEPROP 1 LAST BODY_TYPE PLUMBING
J 0
(-3250 1675);
DISPLAY 0.872340 (-3250 1675);
PAINT GREEN (-3250 1675);
DISPLAY INVISIBLE (-3250 1675);
FORCEPROP 1 LAST HDL_TAP TRUE
J 0
(-2925 1500);
DISPLAY 0.872340 (-2925 1500);
DISPLAY INVISIBLE (-2925 1500);
FORCEPROP 1 LAST PATH I243
J 0
(-3252 1625);
DISPLAY 0.872340 (-3252 1625);
PAINT GREEN (-3252 1625);
DISPLAY INVISIBLE (-3252 1625);
FORCEADD TAP..1
R 2
(-5675 5975);
FORCEPROP 3 LASTPIN (-5625 5975) SIG_NAME M_I_CPU0_SA_DQS_DP<0>
J 0
(-5615 5985);
DISPLAY 0.659574 (-5615 5985);
PAINT MONO (-5615 5985);
DISPLAY INVISIBLE (-5615 5985);
FORCEPROP 1 LASTPIN (-5625 5975) BN 0
J 2
(-5613 5983);
DISPLAY 0.489362 (-5613 5983);
PAINT GREEN (-5613 5983);
FORCEPROP 2 LAST CDS_LIB mstr_standard
J 2
(-5675 5975);
DISPLAY 0.723404 (-5675 5975);
PAINT MONO (-5675 5975);
DISPLAY INVISIBLE (-5675 5975);
FORCEPROP 1 LAST BODY_TYPE PLUMBING
J 2
(-5675 6025);
DISPLAY 0.872340 (-5675 6025);
PAINT GREEN (-5675 6025);
DISPLAY INVISIBLE (-5675 6025);
FORCEPROP 1 LAST HDL_TAP TRUE
J 2
(-6000 5850);
DISPLAY 0.872340 (-6000 5850);
DISPLAY INVISIBLE (-6000 5850);
FORCEPROP 1 LAST PATH I244
J 2
(-5673 5975);
DISPLAY 0.872340 (-5673 5975);
PAINT GREEN (-5673 5975);
DISPLAY INVISIBLE (-5673 5975);
FORCEADD TAP..1
R 2
(-5675 5875);
FORCEPROP 3 LASTPIN (-5625 5875) SIG_NAME M_I_CPU0_SA_DQS_DP<1>
J 0
(-5615 5885);
DISPLAY 0.659574 (-5615 5885);
PAINT MONO (-5615 5885);
DISPLAY INVISIBLE (-5615 5885);
FORCEPROP 1 LASTPIN (-5625 5875) BN 1
J 2
(-5613 5883);
DISPLAY 0.489362 (-5613 5883);
PAINT GREEN (-5613 5883);
FORCEPROP 2 LAST CDS_LIB mstr_standard
J 2
(-5675 5875);
DISPLAY 0.723404 (-5675 5875);
PAINT MONO (-5675 5875);
DISPLAY INVISIBLE (-5675 5875);
FORCEPROP 1 LAST BODY_TYPE PLUMBING
J 2
(-5675 5925);
DISPLAY 0.872340 (-5675 5925);
PAINT GREEN (-5675 5925);
DISPLAY INVISIBLE (-5675 5925);
FORCEPROP 1 LAST HDL_TAP TRUE
J 2
(-6000 5750);
DISPLAY 0.872340 (-6000 5750);
DISPLAY INVISIBLE (-6000 5750);
FORCEPROP 1 LAST PATH I245
J 2
(-5673 5875);
DISPLAY 0.872340 (-5673 5875);
PAINT GREEN (-5673 5875);
DISPLAY INVISIBLE (-5673 5875);
FORCEADD TAP..1
R 2
(-5675 5775);
FORCEPROP 3 LASTPIN (-5625 5775) SIG_NAME M_I_CPU0_SA_DQS_DP<2>
J 0
(-5615 5785);
DISPLAY 0.659574 (-5615 5785);
PAINT MONO (-5615 5785);
DISPLAY INVISIBLE (-5615 5785);
FORCEPROP 1 LASTPIN (-5625 5775) BN 2
J 2
(-5613 5783);
DISPLAY 0.489362 (-5613 5783);
PAINT GREEN (-5613 5783);
FORCEPROP 2 LAST CDS_LIB mstr_standard
J 2
(-5675 5775);
DISPLAY 0.723404 (-5675 5775);
PAINT MONO (-5675 5775);
DISPLAY INVISIBLE (-5675 5775);
FORCEPROP 1 LAST BODY_TYPE PLUMBING
J 2
(-5675 5825);
DISPLAY 0.872340 (-5675 5825);
PAINT GREEN (-5675 5825);
DISPLAY INVISIBLE (-5675 5825);
FORCEPROP 1 LAST HDL_TAP TRUE
J 2
(-6000 5650);
DISPLAY 0.872340 (-6000 5650);
DISPLAY INVISIBLE (-6000 5650);
FORCEPROP 1 LAST PATH I246
J 2
(-5673 5775);
DISPLAY 0.872340 (-5673 5775);
PAINT GREEN (-5673 5775);
DISPLAY INVISIBLE (-5673 5775);
FORCEADD TAP..1
R 2
(-5675 5675);
FORCEPROP 3 LASTPIN (-5625 5675) SIG_NAME M_I_CPU0_SA_DQS_DP<3>
J 0
(-5615 5685);
DISPLAY 0.659574 (-5615 5685);
PAINT MONO (-5615 5685);
DISPLAY INVISIBLE (-5615 5685);
FORCEPROP 1 LASTPIN (-5625 5675) BN 3
J 2
(-5613 5683);
DISPLAY 0.489362 (-5613 5683);
PAINT GREEN (-5613 5683);
FORCEPROP 2 LAST CDS_LIB mstr_standard
J 2
(-5675 5675);
DISPLAY 0.723404 (-5675 5675);
PAINT MONO (-5675 5675);
DISPLAY INVISIBLE (-5675 5675);
FORCEPROP 1 LAST BODY_TYPE PLUMBING
J 2
(-5675 5725);
DISPLAY 0.872340 (-5675 5725);
PAINT GREEN (-5675 5725);
DISPLAY INVISIBLE (-5675 5725);
FORCEPROP 1 LAST HDL_TAP TRUE
J 2
(-6000 5550);
DISPLAY 0.872340 (-6000 5550);
DISPLAY INVISIBLE (-6000 5550);
FORCEPROP 1 LAST PATH I247
J 2
(-5673 5675);
DISPLAY 0.872340 (-5673 5675);
PAINT GREEN (-5673 5675);
DISPLAY INVISIBLE (-5673 5675);
FORCEADD TAP..1
R 2
(-5675 5575);
FORCEPROP 3 LASTPIN (-5625 5575) SIG_NAME M_I_CPU0_SA_DQS_DP<4>
J 0
(-5615 5585);
DISPLAY 0.659574 (-5615 5585);
PAINT MONO (-5615 5585);
DISPLAY INVISIBLE (-5615 5585);
FORCEPROP 1 LASTPIN (-5625 5575) BN 4
J 2
(-5613 5583);
DISPLAY 0.489362 (-5613 5583);
PAINT GREEN (-5613 5583);
FORCEPROP 2 LAST CDS_LIB mstr_standard
J 2
(-5675 5575);
DISPLAY 0.723404 (-5675 5575);
PAINT MONO (-5675 5575);
DISPLAY INVISIBLE (-5675 5575);
FORCEPROP 1 LAST BODY_TYPE PLUMBING
J 2
(-5675 5625);
DISPLAY 0.872340 (-5675 5625);
PAINT GREEN (-5675 5625);
DISPLAY INVISIBLE (-5675 5625);
FORCEPROP 1 LAST HDL_TAP TRUE
J 2
(-6000 5450);
DISPLAY 0.872340 (-6000 5450);
DISPLAY INVISIBLE (-6000 5450);
FORCEPROP 1 LAST PATH I248
J 2
(-5673 5575);
DISPLAY 0.872340 (-5673 5575);
PAINT GREEN (-5673 5575);
DISPLAY INVISIBLE (-5673 5575);
FORCEADD TAP..1
R 2
(-5675 5475);
FORCEPROP 3 LASTPIN (-5625 5475) SIG_NAME M_I_CPU0_SA_DQS_DP<5>
J 0
(-5615 5485);
DISPLAY 0.659574 (-5615 5485);
PAINT MONO (-5615 5485);
DISPLAY INVISIBLE (-5615 5485);
FORCEPROP 1 LASTPIN (-5625 5475) BN 5
J 2
(-5613 5483);
DISPLAY 0.489362 (-5613 5483);
PAINT GREEN (-5613 5483);
FORCEPROP 2 LAST CDS_LIB mstr_standard
J 2
(-5675 5475);
DISPLAY 0.723404 (-5675 5475);
PAINT MONO (-5675 5475);
DISPLAY INVISIBLE (-5675 5475);
FORCEPROP 1 LAST BODY_TYPE PLUMBING
J 2
(-5675 5525);
DISPLAY 0.872340 (-5675 5525);
PAINT GREEN (-5675 5525);
DISPLAY INVISIBLE (-5675 5525);
FORCEPROP 1 LAST HDL_TAP TRUE
J 2
(-6000 5350);
DISPLAY 0.872340 (-6000 5350);
DISPLAY INVISIBLE (-6000 5350);
FORCEPROP 1 LAST PATH I249
J 2
(-5673 5475);
DISPLAY 0.872340 (-5673 5475);
PAINT GREEN (-5673 5475);
DISPLAY INVISIBLE (-5673 5475);
FORCEADD TAP..1
R 2
(-5675 5375);
FORCEPROP 3 LASTPIN (-5625 5375) SIG_NAME M_I_CPU0_SA_DQS_DP<6>
J 0
(-5615 5385);
DISPLAY 0.659574 (-5615 5385);
PAINT MONO (-5615 5385);
DISPLAY INVISIBLE (-5615 5385);
FORCEPROP 1 LASTPIN (-5625 5375) BN 6
J 2
(-5613 5383);
DISPLAY 0.489362 (-5613 5383);
PAINT GREEN (-5613 5383);
FORCEPROP 2 LAST CDS_LIB mstr_standard
J 2
(-5675 5375);
DISPLAY 0.723404 (-5675 5375);
PAINT MONO (-5675 5375);
DISPLAY INVISIBLE (-5675 5375);
FORCEPROP 1 LAST BODY_TYPE PLUMBING
J 2
(-5675 5425);
DISPLAY 0.872340 (-5675 5425);
PAINT GREEN (-5675 5425);
DISPLAY INVISIBLE (-5675 5425);
FORCEPROP 1 LAST HDL_TAP TRUE
J 2
(-6000 5250);
DISPLAY 0.872340 (-6000 5250);
DISPLAY INVISIBLE (-6000 5250);
FORCEPROP 1 LAST PATH I250
J 2
(-5673 5375);
DISPLAY 0.872340 (-5673 5375);
PAINT GREEN (-5673 5375);
DISPLAY INVISIBLE (-5673 5375);
FORCEADD TAP..1
R 2
(-5675 5275);
FORCEPROP 3 LASTPIN (-5625 5275) SIG_NAME M_I_CPU0_SA_DQS_DP<7>
J 0
(-5615 5285);
DISPLAY 0.659574 (-5615 5285);
PAINT MONO (-5615 5285);
DISPLAY INVISIBLE (-5615 5285);
FORCEPROP 1 LASTPIN (-5625 5275) BN 7
J 2
(-5613 5283);
DISPLAY 0.489362 (-5613 5283);
PAINT GREEN (-5613 5283);
FORCEPROP 2 LAST CDS_LIB mstr_standard
J 2
(-5675 5275);
DISPLAY 0.723404 (-5675 5275);
PAINT MONO (-5675 5275);
DISPLAY INVISIBLE (-5675 5275);
FORCEPROP 1 LAST BODY_TYPE PLUMBING
J 2
(-5675 5325);
DISPLAY 0.872340 (-5675 5325);
PAINT GREEN (-5675 5325);
DISPLAY INVISIBLE (-5675 5325);
FORCEPROP 1 LAST HDL_TAP TRUE
J 2
(-6000 5150);
DISPLAY 0.872340 (-6000 5150);
DISPLAY INVISIBLE (-6000 5150);
FORCEPROP 1 LAST PATH I251
J 2
(-5673 5275);
DISPLAY 0.872340 (-5673 5275);
PAINT GREEN (-5673 5275);
DISPLAY INVISIBLE (-5673 5275);
FORCEADD TAP..1
R 2
(-5675 5175);
FORCEPROP 3 LASTPIN (-5625 5175) SIG_NAME M_I_CPU0_SA_DQS_DP<8>
J 0
(-5615 5185);
DISPLAY 0.659574 (-5615 5185);
PAINT MONO (-5615 5185);
DISPLAY INVISIBLE (-5615 5185);
FORCEPROP 1 LASTPIN (-5625 5175) BN 8
J 2
(-5613 5183);
DISPLAY 0.489362 (-5613 5183);
PAINT GREEN (-5613 5183);
FORCEPROP 2 LAST CDS_LIB mstr_standard
J 2
(-5675 5175);
DISPLAY 0.723404 (-5675 5175);
PAINT MONO (-5675 5175);
DISPLAY INVISIBLE (-5675 5175);
FORCEPROP 1 LAST BODY_TYPE PLUMBING
J 2
(-5675 5225);
DISPLAY 0.872340 (-5675 5225);
PAINT GREEN (-5675 5225);
DISPLAY INVISIBLE (-5675 5225);
FORCEPROP 1 LAST HDL_TAP TRUE
J 2
(-6000 5050);
DISPLAY 0.872340 (-6000 5050);
DISPLAY INVISIBLE (-6000 5050);
FORCEPROP 1 LAST PATH I252
J 2
(-5673 5175);
DISPLAY 0.872340 (-5673 5175);
PAINT GREEN (-5673 5175);
DISPLAY INVISIBLE (-5673 5175);
FORCEADD TAP..1
R 2
(-5875 5925);
FORCEPROP 3 LASTPIN (-5825 5925) SIG_NAME M_I_CPU0_SA_DQS_DN<0>
J 0
(-5815 5935);
DISPLAY 0.659574 (-5815 5935);
PAINT MONO (-5815 5935);
DISPLAY INVISIBLE (-5815 5935);
FORCEPROP 1 LASTPIN (-5825 5925) BN 0
J 2
(-5813 5933);
DISPLAY 0.489362 (-5813 5933);
PAINT GREEN (-5813 5933);
FORCEPROP 2 LAST CDS_LIB mstr_standard
J 2
(-5875 5925);
DISPLAY 0.723404 (-5875 5925);
PAINT MONO (-5875 5925);
DISPLAY INVISIBLE (-5875 5925);
FORCEPROP 1 LAST BODY_TYPE PLUMBING
J 2
(-5875 5975);
DISPLAY 0.872340 (-5875 5975);
PAINT GREEN (-5875 5975);
DISPLAY INVISIBLE (-5875 5975);
FORCEPROP 1 LAST HDL_TAP TRUE
J 2
(-6200 5800);
DISPLAY 0.872340 (-6200 5800);
DISPLAY INVISIBLE (-6200 5800);
FORCEPROP 1 LAST PATH I253
J 2
(-5873 5925);
DISPLAY 0.872340 (-5873 5925);
PAINT GREEN (-5873 5925);
DISPLAY INVISIBLE (-5873 5925);
FORCEADD TAP..1
R 2
(-5875 5825);
FORCEPROP 3 LASTPIN (-5825 5825) SIG_NAME M_I_CPU0_SA_DQS_DN<1>
J 0
(-5815 5835);
DISPLAY 0.659574 (-5815 5835);
PAINT MONO (-5815 5835);
DISPLAY INVISIBLE (-5815 5835);
FORCEPROP 1 LASTPIN (-5825 5825) BN 1
J 2
(-5813 5833);
DISPLAY 0.489362 (-5813 5833);
PAINT GREEN (-5813 5833);
FORCEPROP 2 LAST CDS_LIB mstr_standard
J 2
(-5875 5825);
DISPLAY 0.723404 (-5875 5825);
PAINT MONO (-5875 5825);
DISPLAY INVISIBLE (-5875 5825);
FORCEPROP 1 LAST BODY_TYPE PLUMBING
J 2
(-5875 5875);
DISPLAY 0.872340 (-5875 5875);
PAINT GREEN (-5875 5875);
DISPLAY INVISIBLE (-5875 5875);
FORCEPROP 1 LAST HDL_TAP TRUE
J 2
(-6200 5700);
DISPLAY 0.872340 (-6200 5700);
DISPLAY INVISIBLE (-6200 5700);
FORCEPROP 1 LAST PATH I254
J 2
(-5873 5825);
DISPLAY 0.872340 (-5873 5825);
PAINT GREEN (-5873 5825);
DISPLAY INVISIBLE (-5873 5825);
FORCEADD TAP..1
R 2
(-5875 5725);
FORCEPROP 3 LASTPIN (-5825 5725) SIG_NAME M_I_CPU0_SA_DQS_DN<2>
J 0
(-5815 5735);
DISPLAY 0.659574 (-5815 5735);
PAINT MONO (-5815 5735);
DISPLAY INVISIBLE (-5815 5735);
FORCEPROP 1 LASTPIN (-5825 5725) BN 2
J 2
(-5813 5733);
DISPLAY 0.489362 (-5813 5733);
PAINT GREEN (-5813 5733);
FORCEPROP 2 LAST CDS_LIB mstr_standard
J 2
(-5875 5725);
DISPLAY 0.723404 (-5875 5725);
PAINT MONO (-5875 5725);
DISPLAY INVISIBLE (-5875 5725);
FORCEPROP 1 LAST BODY_TYPE PLUMBING
J 2
(-5875 5775);
DISPLAY 0.872340 (-5875 5775);
PAINT GREEN (-5875 5775);
DISPLAY INVISIBLE (-5875 5775);
FORCEPROP 1 LAST HDL_TAP TRUE
J 2
(-6200 5600);
DISPLAY 0.872340 (-6200 5600);
DISPLAY INVISIBLE (-6200 5600);
FORCEPROP 1 LAST PATH I255
J 2
(-5873 5725);
DISPLAY 0.872340 (-5873 5725);
PAINT GREEN (-5873 5725);
DISPLAY INVISIBLE (-5873 5725);
FORCEADD TAP..1
R 2
(-5875 5525);
FORCEPROP 3 LASTPIN (-5825 5525) SIG_NAME M_I_CPU0_SA_DQS_DN<4>
J 0
(-5815 5535);
DISPLAY 0.659574 (-5815 5535);
PAINT MONO (-5815 5535);
DISPLAY INVISIBLE (-5815 5535);
FORCEPROP 1 LASTPIN (-5825 5525) BN 4
J 2
(-5813 5533);
DISPLAY 0.489362 (-5813 5533);
PAINT GREEN (-5813 5533);
FORCEPROP 2 LAST CDS_LIB mstr_standard
J 2
(-5875 5525);
DISPLAY 0.723404 (-5875 5525);
PAINT MONO (-5875 5525);
DISPLAY INVISIBLE (-5875 5525);
FORCEPROP 1 LAST BODY_TYPE PLUMBING
J 2
(-5875 5575);
DISPLAY 0.872340 (-5875 5575);
PAINT GREEN (-5875 5575);
DISPLAY INVISIBLE (-5875 5575);
FORCEPROP 1 LAST HDL_TAP TRUE
J 2
(-6200 5400);
DISPLAY 0.872340 (-6200 5400);
DISPLAY INVISIBLE (-6200 5400);
FORCEPROP 1 LAST PATH I256
J 2
(-5873 5525);
DISPLAY 0.872340 (-5873 5525);
PAINT GREEN (-5873 5525);
DISPLAY INVISIBLE (-5873 5525);
FORCEADD TAP..1
R 2
(-5875 5625);
FORCEPROP 3 LASTPIN (-5825 5625) SIG_NAME M_I_CPU0_SA_DQS_DN<3>
J 0
(-5815 5635);
DISPLAY 0.659574 (-5815 5635);
PAINT MONO (-5815 5635);
DISPLAY INVISIBLE (-5815 5635);
FORCEPROP 1 LASTPIN (-5825 5625) BN 3
J 2
(-5813 5633);
DISPLAY 0.489362 (-5813 5633);
PAINT GREEN (-5813 5633);
FORCEPROP 2 LAST CDS_LIB mstr_standard
J 2
(-5875 5625);
DISPLAY 0.723404 (-5875 5625);
PAINT MONO (-5875 5625);
DISPLAY INVISIBLE (-5875 5625);
FORCEPROP 1 LAST BODY_TYPE PLUMBING
J 2
(-5875 5675);
DISPLAY 0.872340 (-5875 5675);
PAINT GREEN (-5875 5675);
DISPLAY INVISIBLE (-5875 5675);
FORCEPROP 1 LAST HDL_TAP TRUE
J 2
(-6200 5500);
DISPLAY 0.872340 (-6200 5500);
DISPLAY INVISIBLE (-6200 5500);
FORCEPROP 1 LAST PATH I257
J 2
(-5873 5625);
DISPLAY 0.872340 (-5873 5625);
PAINT GREEN (-5873 5625);
DISPLAY INVISIBLE (-5873 5625);
FORCEADD TAP..1
R 2
(-5875 5425);
FORCEPROP 3 LASTPIN (-5825 5425) SIG_NAME M_I_CPU0_SA_DQS_DN<5>
J 0
(-5815 5435);
DISPLAY 0.659574 (-5815 5435);
PAINT MONO (-5815 5435);
DISPLAY INVISIBLE (-5815 5435);
FORCEPROP 1 LASTPIN (-5825 5425) BN 5
J 2
(-5813 5433);
DISPLAY 0.489362 (-5813 5433);
PAINT GREEN (-5813 5433);
FORCEPROP 2 LAST CDS_LIB mstr_standard
J 2
(-5875 5425);
DISPLAY 0.723404 (-5875 5425);
PAINT MONO (-5875 5425);
DISPLAY INVISIBLE (-5875 5425);
FORCEPROP 1 LAST BODY_TYPE PLUMBING
J 2
(-5875 5475);
DISPLAY 0.872340 (-5875 5475);
PAINT GREEN (-5875 5475);
DISPLAY INVISIBLE (-5875 5475);
FORCEPROP 1 LAST HDL_TAP TRUE
J 2
(-6200 5300);
DISPLAY 0.872340 (-6200 5300);
DISPLAY INVISIBLE (-6200 5300);
FORCEPROP 1 LAST PATH I258
J 2
(-5873 5425);
DISPLAY 0.872340 (-5873 5425);
PAINT GREEN (-5873 5425);
DISPLAY INVISIBLE (-5873 5425);
FORCEADD TAP..1
R 2
(-5875 5325);
FORCEPROP 3 LASTPIN (-5825 5325) SIG_NAME M_I_CPU0_SA_DQS_DN<6>
J 0
(-5815 5335);
DISPLAY 0.659574 (-5815 5335);
PAINT MONO (-5815 5335);
DISPLAY INVISIBLE (-5815 5335);
FORCEPROP 1 LASTPIN (-5825 5325) BN 6
J 2
(-5813 5333);
DISPLAY 0.489362 (-5813 5333);
PAINT GREEN (-5813 5333);
FORCEPROP 2 LAST CDS_LIB mstr_standard
J 2
(-5875 5325);
DISPLAY 0.723404 (-5875 5325);
PAINT MONO (-5875 5325);
DISPLAY INVISIBLE (-5875 5325);
FORCEPROP 1 LAST BODY_TYPE PLUMBING
J 2
(-5875 5375);
DISPLAY 0.872340 (-5875 5375);
PAINT GREEN (-5875 5375);
DISPLAY INVISIBLE (-5875 5375);
FORCEPROP 1 LAST HDL_TAP TRUE
J 2
(-6200 5200);
DISPLAY 0.872340 (-6200 5200);
DISPLAY INVISIBLE (-6200 5200);
FORCEPROP 1 LAST PATH I259
J 2
(-5873 5325);
DISPLAY 0.872340 (-5873 5325);
PAINT GREEN (-5873 5325);
DISPLAY INVISIBLE (-5873 5325);
FORCEADD TAP..1
R 2
(-5875 5225);
FORCEPROP 3 LASTPIN (-5825 5225) SIG_NAME M_I_CPU0_SA_DQS_DN<7>
J 0
(-5815 5235);
DISPLAY 0.659574 (-5815 5235);
PAINT MONO (-5815 5235);
DISPLAY INVISIBLE (-5815 5235);
FORCEPROP 1 LASTPIN (-5825 5225) BN 7
J 2
(-5813 5233);
DISPLAY 0.489362 (-5813 5233);
PAINT GREEN (-5813 5233);
FORCEPROP 2 LAST CDS_LIB mstr_standard
J 2
(-5875 5225);
DISPLAY 0.723404 (-5875 5225);
PAINT MONO (-5875 5225);
DISPLAY INVISIBLE (-5875 5225);
FORCEPROP 1 LAST BODY_TYPE PLUMBING
J 2
(-5875 5275);
DISPLAY 0.872340 (-5875 5275);
PAINT GREEN (-5875 5275);
DISPLAY INVISIBLE (-5875 5275);
FORCEPROP 1 LAST HDL_TAP TRUE
J 2
(-6200 5100);
DISPLAY 0.872340 (-6200 5100);
DISPLAY INVISIBLE (-6200 5100);
FORCEPROP 1 LAST PATH I260
J 2
(-5873 5225);
DISPLAY 0.872340 (-5873 5225);
PAINT GREEN (-5873 5225);
DISPLAY INVISIBLE (-5873 5225);
FORCEADD TAP..1
R 2
(-5875 5125);
FORCEPROP 3 LASTPIN (-5825 5125) SIG_NAME M_I_CPU0_SA_DQS_DN<8>
J 0
(-5815 5135);
DISPLAY 0.659574 (-5815 5135);
PAINT MONO (-5815 5135);
DISPLAY INVISIBLE (-5815 5135);
FORCEPROP 1 LASTPIN (-5825 5125) BN 8
J 2
(-5813 5133);
DISPLAY 0.489362 (-5813 5133);
PAINT GREEN (-5813 5133);
FORCEPROP 2 LAST CDS_LIB mstr_standard
J 2
(-5875 5125);
DISPLAY 0.723404 (-5875 5125);
PAINT MONO (-5875 5125);
DISPLAY INVISIBLE (-5875 5125);
FORCEPROP 1 LAST BODY_TYPE PLUMBING
J 2
(-5875 5175);
DISPLAY 0.872340 (-5875 5175);
PAINT GREEN (-5875 5175);
DISPLAY INVISIBLE (-5875 5175);
FORCEPROP 1 LAST HDL_TAP TRUE
J 2
(-6200 5000);
DISPLAY 0.872340 (-6200 5000);
DISPLAY INVISIBLE (-6200 5000);
FORCEPROP 1 LAST PATH I261
J 2
(-5873 5125);
DISPLAY 0.872340 (-5873 5125);
PAINT GREEN (-5873 5125);
DISPLAY INVISIBLE (-5873 5125);
FORCEADD TAP..1
R 2
(-5675 5075);
FORCEPROP 3 LASTPIN (-5625 5075) SIG_NAME M_I_CPU0_SA_DQS_DP<9>
J 0
(-5615 5085);
DISPLAY 0.659574 (-5615 5085);
PAINT MONO (-5615 5085);
DISPLAY INVISIBLE (-5615 5085);
FORCEPROP 1 LASTPIN (-5625 5075) BN 9
J 2
(-5613 5083);
DISPLAY 0.489362 (-5613 5083);
PAINT GREEN (-5613 5083);
FORCEPROP 2 LAST CDS_LIB mstr_standard
J 2
(-5675 5075);
DISPLAY 0.723404 (-5675 5075);
PAINT MONO (-5675 5075);
DISPLAY INVISIBLE (-5675 5075);
FORCEPROP 1 LAST BODY_TYPE PLUMBING
J 2
(-5675 5125);
DISPLAY 0.872340 (-5675 5125);
PAINT GREEN (-5675 5125);
DISPLAY INVISIBLE (-5675 5125);
FORCEPROP 1 LAST HDL_TAP TRUE
J 2
(-6000 4950);
DISPLAY 0.872340 (-6000 4950);
DISPLAY INVISIBLE (-6000 4950);
FORCEPROP 1 LAST PATH I262
J 2
(-5673 5075);
DISPLAY 0.872340 (-5673 5075);
PAINT GREEN (-5673 5075);
DISPLAY INVISIBLE (-5673 5075);
FORCEADD TAP..1
R 2
(-5675 4925);
FORCEPROP 3 LASTPIN (-5625 4925) SIG_NAME M_I_CPU0_SB_DQS_DP<0>
J 0
(-5615 4935);
DISPLAY 0.659574 (-5615 4935);
PAINT MONO (-5615 4935);
DISPLAY INVISIBLE (-5615 4935);
FORCEPROP 1 LASTPIN (-5625 4925) BN 0
J 2
(-5613 4933);
DISPLAY 0.489362 (-5613 4933);
PAINT GREEN (-5613 4933);
FORCEPROP 2 LAST CDS_LIB mstr_standard
J 2
(-5675 4925);
DISPLAY 0.723404 (-5675 4925);
PAINT MONO (-5675 4925);
DISPLAY INVISIBLE (-5675 4925);
FORCEPROP 1 LAST BODY_TYPE PLUMBING
J 2
(-5675 4975);
DISPLAY 0.872340 (-5675 4975);
PAINT GREEN (-5675 4975);
DISPLAY INVISIBLE (-5675 4975);
FORCEPROP 1 LAST HDL_TAP TRUE
J 2
(-6000 4800);
DISPLAY 0.872340 (-6000 4800);
DISPLAY INVISIBLE (-6000 4800);
FORCEPROP 1 LAST PATH I263
J 2
(-5673 4925);
DISPLAY 0.872340 (-5673 4925);
PAINT GREEN (-5673 4925);
DISPLAY INVISIBLE (-5673 4925);
FORCEADD TAP..1
R 2
(-5675 4825);
FORCEPROP 3 LASTPIN (-5625 4825) SIG_NAME M_I_CPU0_SB_DQS_DP<1>
J 0
(-5615 4835);
DISPLAY 0.659574 (-5615 4835);
PAINT MONO (-5615 4835);
DISPLAY INVISIBLE (-5615 4835);
FORCEPROP 1 LASTPIN (-5625 4825) BN 1
J 2
(-5613 4833);
DISPLAY 0.489362 (-5613 4833);
PAINT GREEN (-5613 4833);
FORCEPROP 2 LAST CDS_LIB mstr_standard
J 2
(-5675 4825);
DISPLAY 0.723404 (-5675 4825);
PAINT MONO (-5675 4825);
DISPLAY INVISIBLE (-5675 4825);
FORCEPROP 1 LAST BODY_TYPE PLUMBING
J 2
(-5675 4875);
DISPLAY 0.872340 (-5675 4875);
PAINT GREEN (-5675 4875);
DISPLAY INVISIBLE (-5675 4875);
FORCEPROP 1 LAST HDL_TAP TRUE
J 2
(-6000 4700);
DISPLAY 0.872340 (-6000 4700);
DISPLAY INVISIBLE (-6000 4700);
FORCEPROP 1 LAST PATH I264
J 2
(-5673 4825);
DISPLAY 0.872340 (-5673 4825);
PAINT GREEN (-5673 4825);
DISPLAY INVISIBLE (-5673 4825);
FORCEADD TAP..1
R 2
(-5675 4725);
FORCEPROP 3 LASTPIN (-5625 4725) SIG_NAME M_I_CPU0_SB_DQS_DP<2>
J 0
(-5615 4735);
DISPLAY 0.659574 (-5615 4735);
PAINT MONO (-5615 4735);
DISPLAY INVISIBLE (-5615 4735);
FORCEPROP 1 LASTPIN (-5625 4725) BN 2
J 2
(-5613 4733);
DISPLAY 0.489362 (-5613 4733);
PAINT GREEN (-5613 4733);
FORCEPROP 2 LAST CDS_LIB mstr_standard
J 2
(-5675 4725);
DISPLAY 0.723404 (-5675 4725);
PAINT MONO (-5675 4725);
DISPLAY INVISIBLE (-5675 4725);
FORCEPROP 1 LAST BODY_TYPE PLUMBING
J 2
(-5675 4775);
DISPLAY 0.872340 (-5675 4775);
PAINT GREEN (-5675 4775);
DISPLAY INVISIBLE (-5675 4775);
FORCEPROP 1 LAST HDL_TAP TRUE
J 2
(-6000 4600);
DISPLAY 0.872340 (-6000 4600);
DISPLAY INVISIBLE (-6000 4600);
FORCEPROP 1 LAST PATH I265
J 2
(-5673 4725);
DISPLAY 0.872340 (-5673 4725);
PAINT GREEN (-5673 4725);
DISPLAY INVISIBLE (-5673 4725);
FORCEADD TAP..1
R 2
(-5675 4625);
FORCEPROP 3 LASTPIN (-5625 4625) SIG_NAME M_I_CPU0_SB_DQS_DP<3>
J 0
(-5615 4635);
DISPLAY 0.659574 (-5615 4635);
PAINT MONO (-5615 4635);
DISPLAY INVISIBLE (-5615 4635);
FORCEPROP 1 LASTPIN (-5625 4625) BN 3
J 2
(-5613 4633);
DISPLAY 0.489362 (-5613 4633);
PAINT GREEN (-5613 4633);
FORCEPROP 2 LAST CDS_LIB mstr_standard
J 2
(-5675 4625);
DISPLAY 0.723404 (-5675 4625);
PAINT MONO (-5675 4625);
DISPLAY INVISIBLE (-5675 4625);
FORCEPROP 1 LAST BODY_TYPE PLUMBING
J 2
(-5675 4675);
DISPLAY 0.872340 (-5675 4675);
PAINT GREEN (-5675 4675);
DISPLAY INVISIBLE (-5675 4675);
FORCEPROP 1 LAST HDL_TAP TRUE
J 2
(-6000 4500);
DISPLAY 0.872340 (-6000 4500);
DISPLAY INVISIBLE (-6000 4500);
FORCEPROP 1 LAST PATH I266
J 2
(-5673 4625);
DISPLAY 0.872340 (-5673 4625);
PAINT GREEN (-5673 4625);
DISPLAY INVISIBLE (-5673 4625);
FORCEADD TAP..1
R 2
(-5675 4525);
FORCEPROP 3 LASTPIN (-5625 4525) SIG_NAME M_I_CPU0_SB_DQS_DP<4>
J 0
(-5615 4535);
DISPLAY 0.659574 (-5615 4535);
PAINT MONO (-5615 4535);
DISPLAY INVISIBLE (-5615 4535);
FORCEPROP 1 LASTPIN (-5625 4525) BN 4
J 2
(-5613 4533);
DISPLAY 0.489362 (-5613 4533);
PAINT GREEN (-5613 4533);
FORCEPROP 2 LAST CDS_LIB mstr_standard
J 2
(-5675 4525);
DISPLAY 0.723404 (-5675 4525);
PAINT MONO (-5675 4525);
DISPLAY INVISIBLE (-5675 4525);
FORCEPROP 1 LAST BODY_TYPE PLUMBING
J 2
(-5675 4575);
DISPLAY 0.872340 (-5675 4575);
PAINT GREEN (-5675 4575);
DISPLAY INVISIBLE (-5675 4575);
FORCEPROP 1 LAST HDL_TAP TRUE
J 2
(-6000 4400);
DISPLAY 0.872340 (-6000 4400);
DISPLAY INVISIBLE (-6000 4400);
FORCEPROP 1 LAST PATH I267
J 2
(-5673 4525);
DISPLAY 0.872340 (-5673 4525);
PAINT GREEN (-5673 4525);
DISPLAY INVISIBLE (-5673 4525);
FORCEADD TAP..1
R 2
(-5675 4425);
FORCEPROP 3 LASTPIN (-5625 4425) SIG_NAME M_I_CPU0_SB_DQS_DP<5>
J 0
(-5615 4435);
DISPLAY 0.659574 (-5615 4435);
PAINT MONO (-5615 4435);
DISPLAY INVISIBLE (-5615 4435);
FORCEPROP 1 LASTPIN (-5625 4425) BN 5
J 2
(-5613 4433);
DISPLAY 0.489362 (-5613 4433);
PAINT GREEN (-5613 4433);
FORCEPROP 2 LAST CDS_LIB mstr_standard
J 2
(-5675 4425);
DISPLAY 0.723404 (-5675 4425);
PAINT MONO (-5675 4425);
DISPLAY INVISIBLE (-5675 4425);
FORCEPROP 1 LAST BODY_TYPE PLUMBING
J 2
(-5675 4475);
DISPLAY 0.872340 (-5675 4475);
PAINT GREEN (-5675 4475);
DISPLAY INVISIBLE (-5675 4475);
FORCEPROP 1 LAST HDL_TAP TRUE
J 2
(-6000 4300);
DISPLAY 0.872340 (-6000 4300);
DISPLAY INVISIBLE (-6000 4300);
FORCEPROP 1 LAST PATH I268
J 2
(-5673 4425);
DISPLAY 0.872340 (-5673 4425);
PAINT GREEN (-5673 4425);
DISPLAY INVISIBLE (-5673 4425);
FORCEADD TAP..1
R 2
(-5675 4325);
FORCEPROP 3 LASTPIN (-5625 4325) SIG_NAME M_I_CPU0_SB_DQS_DP<6>
J 0
(-5615 4335);
DISPLAY 0.659574 (-5615 4335);
PAINT MONO (-5615 4335);
DISPLAY INVISIBLE (-5615 4335);
FORCEPROP 1 LASTPIN (-5625 4325) BN 6
J 2
(-5613 4333);
DISPLAY 0.489362 (-5613 4333);
PAINT GREEN (-5613 4333);
FORCEPROP 2 LAST CDS_LIB mstr_standard
J 2
(-5675 4325);
DISPLAY 0.723404 (-5675 4325);
PAINT MONO (-5675 4325);
DISPLAY INVISIBLE (-5675 4325);
FORCEPROP 1 LAST BODY_TYPE PLUMBING
J 2
(-5675 4375);
DISPLAY 0.872340 (-5675 4375);
PAINT GREEN (-5675 4375);
DISPLAY INVISIBLE (-5675 4375);
FORCEPROP 1 LAST HDL_TAP TRUE
J 2
(-6000 4200);
DISPLAY 0.872340 (-6000 4200);
DISPLAY INVISIBLE (-6000 4200);
FORCEPROP 1 LAST PATH I269
J 2
(-5673 4325);
DISPLAY 0.872340 (-5673 4325);
PAINT GREEN (-5673 4325);
DISPLAY INVISIBLE (-5673 4325);
FORCEADD TAP..1
R 2
(-5675 4225);
FORCEPROP 3 LASTPIN (-5625 4225) SIG_NAME M_I_CPU0_SB_DQS_DP<7>
J 0
(-5615 4235);
DISPLAY 0.659574 (-5615 4235);
PAINT MONO (-5615 4235);
DISPLAY INVISIBLE (-5615 4235);
FORCEPROP 1 LASTPIN (-5625 4225) BN 7
J 2
(-5613 4233);
DISPLAY 0.489362 (-5613 4233);
PAINT GREEN (-5613 4233);
FORCEPROP 2 LAST CDS_LIB mstr_standard
J 2
(-5675 4225);
DISPLAY 0.723404 (-5675 4225);
PAINT MONO (-5675 4225);
DISPLAY INVISIBLE (-5675 4225);
FORCEPROP 1 LAST BODY_TYPE PLUMBING
J 2
(-5675 4275);
DISPLAY 0.872340 (-5675 4275);
PAINT GREEN (-5675 4275);
DISPLAY INVISIBLE (-5675 4275);
FORCEPROP 1 LAST HDL_TAP TRUE
J 2
(-6000 4100);
DISPLAY 0.872340 (-6000 4100);
DISPLAY INVISIBLE (-6000 4100);
FORCEPROP 1 LAST PATH I270
J 2
(-5673 4225);
DISPLAY 0.872340 (-5673 4225);
PAINT GREEN (-5673 4225);
DISPLAY INVISIBLE (-5673 4225);
FORCEADD TAP..1
R 2
(-5675 4125);
FORCEPROP 3 LASTPIN (-5625 4125) SIG_NAME M_I_CPU0_SB_DQS_DP<8>
J 0
(-5615 4135);
DISPLAY 0.659574 (-5615 4135);
PAINT MONO (-5615 4135);
DISPLAY INVISIBLE (-5615 4135);
FORCEPROP 1 LASTPIN (-5625 4125) BN 8
J 2
(-5613 4133);
DISPLAY 0.489362 (-5613 4133);
PAINT GREEN (-5613 4133);
FORCEPROP 2 LAST CDS_LIB mstr_standard
J 2
(-5675 4125);
DISPLAY 0.723404 (-5675 4125);
PAINT MONO (-5675 4125);
DISPLAY INVISIBLE (-5675 4125);
FORCEPROP 1 LAST BODY_TYPE PLUMBING
J 2
(-5675 4175);
DISPLAY 0.872340 (-5675 4175);
PAINT GREEN (-5675 4175);
DISPLAY INVISIBLE (-5675 4175);
FORCEPROP 1 LAST HDL_TAP TRUE
J 2
(-6000 4000);
DISPLAY 0.872340 (-6000 4000);
DISPLAY INVISIBLE (-6000 4000);
FORCEPROP 1 LAST PATH I271
J 2
(-5673 4125);
DISPLAY 0.872340 (-5673 4125);
PAINT GREEN (-5673 4125);
DISPLAY INVISIBLE (-5673 4125);
FORCEADD TAP..1
R 2
(-5875 4875);
FORCEPROP 3 LASTPIN (-5825 4875) SIG_NAME M_I_CPU0_SB_DQS_DN<0>
J 0
(-5815 4885);
DISPLAY 0.659574 (-5815 4885);
PAINT MONO (-5815 4885);
DISPLAY INVISIBLE (-5815 4885);
FORCEPROP 1 LASTPIN (-5825 4875) BN 0
J 2
(-5813 4883);
DISPLAY 0.489362 (-5813 4883);
PAINT GREEN (-5813 4883);
FORCEPROP 2 LAST CDS_LIB mstr_standard
J 2
(-5875 4875);
DISPLAY 0.723404 (-5875 4875);
PAINT MONO (-5875 4875);
DISPLAY INVISIBLE (-5875 4875);
FORCEPROP 1 LAST BODY_TYPE PLUMBING
J 2
(-5875 4925);
DISPLAY 0.872340 (-5875 4925);
PAINT GREEN (-5875 4925);
DISPLAY INVISIBLE (-5875 4925);
FORCEPROP 1 LAST HDL_TAP TRUE
J 2
(-6200 4750);
DISPLAY 0.872340 (-6200 4750);
DISPLAY INVISIBLE (-6200 4750);
FORCEPROP 1 LAST PATH I272
J 2
(-5873 4875);
DISPLAY 0.872340 (-5873 4875);
PAINT GREEN (-5873 4875);
DISPLAY INVISIBLE (-5873 4875);
FORCEADD TAP..1
R 2
(-5875 5025);
FORCEPROP 3 LASTPIN (-5825 5025) SIG_NAME M_I_CPU0_SA_DQS_DN<9>
J 0
(-5815 5035);
DISPLAY 0.659574 (-5815 5035);
PAINT MONO (-5815 5035);
DISPLAY INVISIBLE (-5815 5035);
FORCEPROP 1 LASTPIN (-5825 5025) BN 9
J 2
(-5813 5033);
DISPLAY 0.489362 (-5813 5033);
PAINT GREEN (-5813 5033);
FORCEPROP 2 LAST CDS_LIB mstr_standard
J 2
(-5875 5025);
DISPLAY 0.723404 (-5875 5025);
PAINT MONO (-5875 5025);
DISPLAY INVISIBLE (-5875 5025);
FORCEPROP 1 LAST BODY_TYPE PLUMBING
J 2
(-5875 5075);
DISPLAY 0.872340 (-5875 5075);
PAINT GREEN (-5875 5075);
DISPLAY INVISIBLE (-5875 5075);
FORCEPROP 1 LAST HDL_TAP TRUE
J 2
(-6200 4900);
DISPLAY 0.872340 (-6200 4900);
DISPLAY INVISIBLE (-6200 4900);
FORCEPROP 1 LAST PATH I273
J 2
(-5873 5025);
DISPLAY 0.872340 (-5873 5025);
PAINT GREEN (-5873 5025);
DISPLAY INVISIBLE (-5873 5025);
FORCEADD TAP..1
R 2
(-5875 4775);
FORCEPROP 3 LASTPIN (-5825 4775) SIG_NAME M_I_CPU0_SB_DQS_DN<1>
J 0
(-5815 4785);
DISPLAY 0.659574 (-5815 4785);
PAINT MONO (-5815 4785);
DISPLAY INVISIBLE (-5815 4785);
FORCEPROP 1 LASTPIN (-5825 4775) BN 1
J 2
(-5813 4783);
DISPLAY 0.489362 (-5813 4783);
PAINT GREEN (-5813 4783);
FORCEPROP 2 LAST CDS_LIB mstr_standard
J 2
(-5875 4775);
DISPLAY 0.723404 (-5875 4775);
PAINT MONO (-5875 4775);
DISPLAY INVISIBLE (-5875 4775);
FORCEPROP 1 LAST BODY_TYPE PLUMBING
J 2
(-5875 4825);
DISPLAY 0.872340 (-5875 4825);
PAINT GREEN (-5875 4825);
DISPLAY INVISIBLE (-5875 4825);
FORCEPROP 1 LAST HDL_TAP TRUE
J 2
(-6200 4650);
DISPLAY 0.872340 (-6200 4650);
DISPLAY INVISIBLE (-6200 4650);
FORCEPROP 1 LAST PATH I274
J 2
(-5873 4775);
DISPLAY 0.872340 (-5873 4775);
PAINT GREEN (-5873 4775);
DISPLAY INVISIBLE (-5873 4775);
FORCEADD TAP..1
R 2
(-5875 4675);
FORCEPROP 3 LASTPIN (-5825 4675) SIG_NAME M_I_CPU0_SB_DQS_DN<2>
J 0
(-5815 4685);
DISPLAY 0.659574 (-5815 4685);
PAINT MONO (-5815 4685);
DISPLAY INVISIBLE (-5815 4685);
FORCEPROP 1 LASTPIN (-5825 4675) BN 2
J 2
(-5813 4683);
DISPLAY 0.489362 (-5813 4683);
PAINT GREEN (-5813 4683);
FORCEPROP 2 LAST CDS_LIB mstr_standard
J 2
(-5875 4675);
DISPLAY 0.723404 (-5875 4675);
PAINT MONO (-5875 4675);
DISPLAY INVISIBLE (-5875 4675);
FORCEPROP 1 LAST BODY_TYPE PLUMBING
J 2
(-5875 4725);
DISPLAY 0.872340 (-5875 4725);
PAINT GREEN (-5875 4725);
DISPLAY INVISIBLE (-5875 4725);
FORCEPROP 1 LAST HDL_TAP TRUE
J 2
(-6200 4550);
DISPLAY 0.872340 (-6200 4550);
DISPLAY INVISIBLE (-6200 4550);
FORCEPROP 1 LAST PATH I275
J 2
(-5873 4675);
DISPLAY 0.872340 (-5873 4675);
PAINT GREEN (-5873 4675);
DISPLAY INVISIBLE (-5873 4675);
FORCEADD TAP..1
R 2
(-5875 4575);
FORCEPROP 3 LASTPIN (-5825 4575) SIG_NAME M_I_CPU0_SB_DQS_DN<3>
J 0
(-5815 4585);
DISPLAY 0.659574 (-5815 4585);
PAINT MONO (-5815 4585);
DISPLAY INVISIBLE (-5815 4585);
FORCEPROP 1 LASTPIN (-5825 4575) BN 3
J 2
(-5813 4583);
DISPLAY 0.489362 (-5813 4583);
PAINT GREEN (-5813 4583);
FORCEPROP 2 LAST CDS_LIB mstr_standard
J 2
(-5875 4575);
DISPLAY 0.723404 (-5875 4575);
PAINT MONO (-5875 4575);
DISPLAY INVISIBLE (-5875 4575);
FORCEPROP 1 LAST BODY_TYPE PLUMBING
J 2
(-5875 4625);
DISPLAY 0.872340 (-5875 4625);
PAINT GREEN (-5875 4625);
DISPLAY INVISIBLE (-5875 4625);
FORCEPROP 1 LAST HDL_TAP TRUE
J 2
(-6200 4450);
DISPLAY 0.872340 (-6200 4450);
DISPLAY INVISIBLE (-6200 4450);
FORCEPROP 1 LAST PATH I276
J 2
(-5873 4575);
DISPLAY 0.872340 (-5873 4575);
PAINT GREEN (-5873 4575);
DISPLAY INVISIBLE (-5873 4575);
FORCEADD TAP..1
R 2
(-5875 4375);
FORCEPROP 3 LASTPIN (-5825 4375) SIG_NAME M_I_CPU0_SB_DQS_DN<5>
J 0
(-5815 4385);
DISPLAY 0.659574 (-5815 4385);
PAINT MONO (-5815 4385);
DISPLAY INVISIBLE (-5815 4385);
FORCEPROP 1 LASTPIN (-5825 4375) BN 5
J 2
(-5813 4383);
DISPLAY 0.489362 (-5813 4383);
PAINT GREEN (-5813 4383);
FORCEPROP 2 LAST CDS_LIB mstr_standard
J 2
(-5875 4375);
DISPLAY 0.723404 (-5875 4375);
PAINT MONO (-5875 4375);
DISPLAY INVISIBLE (-5875 4375);
FORCEPROP 1 LAST BODY_TYPE PLUMBING
J 2
(-5875 4425);
DISPLAY 0.872340 (-5875 4425);
PAINT GREEN (-5875 4425);
DISPLAY INVISIBLE (-5875 4425);
FORCEPROP 1 LAST HDL_TAP TRUE
J 2
(-6200 4250);
DISPLAY 0.872340 (-6200 4250);
DISPLAY INVISIBLE (-6200 4250);
FORCEPROP 1 LAST PATH I277
J 2
(-5873 4375);
DISPLAY 0.872340 (-5873 4375);
PAINT GREEN (-5873 4375);
DISPLAY INVISIBLE (-5873 4375);
FORCEADD TAP..1
R 2
(-5875 4475);
FORCEPROP 3 LASTPIN (-5825 4475) SIG_NAME M_I_CPU0_SB_DQS_DN<4>
J 0
(-5815 4485);
DISPLAY 0.659574 (-5815 4485);
PAINT MONO (-5815 4485);
DISPLAY INVISIBLE (-5815 4485);
FORCEPROP 1 LASTPIN (-5825 4475) BN 4
J 2
(-5813 4483);
DISPLAY 0.489362 (-5813 4483);
PAINT GREEN (-5813 4483);
FORCEPROP 2 LAST CDS_LIB mstr_standard
J 2
(-5875 4475);
DISPLAY 0.723404 (-5875 4475);
PAINT MONO (-5875 4475);
DISPLAY INVISIBLE (-5875 4475);
FORCEPROP 1 LAST BODY_TYPE PLUMBING
J 2
(-5875 4525);
DISPLAY 0.872340 (-5875 4525);
PAINT GREEN (-5875 4525);
DISPLAY INVISIBLE (-5875 4525);
FORCEPROP 1 LAST HDL_TAP TRUE
J 2
(-6200 4350);
DISPLAY 0.872340 (-6200 4350);
DISPLAY INVISIBLE (-6200 4350);
FORCEPROP 1 LAST PATH I278
J 2
(-5873 4475);
DISPLAY 0.872340 (-5873 4475);
PAINT GREEN (-5873 4475);
DISPLAY INVISIBLE (-5873 4475);
FORCEADD TAP..1
R 2
(-5875 4275);
FORCEPROP 3 LASTPIN (-5825 4275) SIG_NAME M_I_CPU0_SB_DQS_DN<6>
J 0
(-5815 4285);
DISPLAY 0.659574 (-5815 4285);
PAINT MONO (-5815 4285);
DISPLAY INVISIBLE (-5815 4285);
FORCEPROP 1 LASTPIN (-5825 4275) BN 6
J 2
(-5813 4283);
DISPLAY 0.489362 (-5813 4283);
PAINT GREEN (-5813 4283);
FORCEPROP 2 LAST CDS_LIB mstr_standard
J 2
(-5875 4275);
DISPLAY 0.723404 (-5875 4275);
PAINT MONO (-5875 4275);
DISPLAY INVISIBLE (-5875 4275);
FORCEPROP 1 LAST BODY_TYPE PLUMBING
J 2
(-5875 4325);
DISPLAY 0.872340 (-5875 4325);
PAINT GREEN (-5875 4325);
DISPLAY INVISIBLE (-5875 4325);
FORCEPROP 1 LAST HDL_TAP TRUE
J 2
(-6200 4150);
DISPLAY 0.872340 (-6200 4150);
DISPLAY INVISIBLE (-6200 4150);
FORCEPROP 1 LAST PATH I279
J 2
(-5873 4275);
DISPLAY 0.872340 (-5873 4275);
PAINT GREEN (-5873 4275);
DISPLAY INVISIBLE (-5873 4275);
FORCEADD TAP..1
R 2
(-5875 4175);
FORCEPROP 3 LASTPIN (-5825 4175) SIG_NAME M_I_CPU0_SB_DQS_DN<7>
J 0
(-5815 4185);
DISPLAY 0.659574 (-5815 4185);
PAINT MONO (-5815 4185);
DISPLAY INVISIBLE (-5815 4185);
FORCEPROP 1 LASTPIN (-5825 4175) BN 7
J 2
(-5813 4183);
DISPLAY 0.489362 (-5813 4183);
PAINT GREEN (-5813 4183);
FORCEPROP 2 LAST CDS_LIB mstr_standard
J 2
(-5875 4175);
DISPLAY 0.723404 (-5875 4175);
PAINT MONO (-5875 4175);
DISPLAY INVISIBLE (-5875 4175);
FORCEPROP 1 LAST BODY_TYPE PLUMBING
J 2
(-5875 4225);
DISPLAY 0.872340 (-5875 4225);
PAINT GREEN (-5875 4225);
DISPLAY INVISIBLE (-5875 4225);
FORCEPROP 1 LAST HDL_TAP TRUE
J 2
(-6200 4050);
DISPLAY 0.872340 (-6200 4050);
DISPLAY INVISIBLE (-6200 4050);
FORCEPROP 1 LAST PATH I280
J 2
(-5873 4175);
DISPLAY 0.872340 (-5873 4175);
PAINT GREEN (-5873 4175);
DISPLAY INVISIBLE (-5873 4175);
FORCEADD OFFPAGE..3
R 2
(-6575 5950);
FORCEPROP 2 LAST $XR0 93 
J 0
(-6854 5950);
DISPLAY 0.638298 (-6854 5950);
PAINT MONO (-6854 5950);
FORCEPROP 2 LAST PATH I281
J 0
(-6875 6000);
DISPLAY 1.021277 (-6875 6000);
DISPLAY INVISIBLE (-6875 6000);
FORCEPROP 1 LAST COMMENT_BODY TRUE
J 2
(-6525 5850);
DISPLAY 0.872340 (-6525 5850);
PAINT GREEN (-6525 5850);
DISPLAY INVISIBLE (-6525 5850);
FORCEPROP 1 LAST OFFPAGE TRUE
J 2
(-6900 5825);
DISPLAY 0.872340 (-6900 5825);
PAINT GREEN (-6900 5825);
DISPLAY INVISIBLE (-6900 5825);
FORCEPROP 2 LAST CDS_LIB standard
J 0
(-6575 5950);
DISPLAY INVISIBLE (-6575 5950);
FORCEADD OFFPAGE..3
R 2
(-6575 6000);
FORCEPROP 2 LAST $XR0 93 
J 0
(-6854 6000);
DISPLAY 0.638298 (-6854 6000);
PAINT MONO (-6854 6000);
FORCEPROP 2 LAST PATH I282
J 0
(-6875 6050);
DISPLAY 1.021277 (-6875 6050);
DISPLAY INVISIBLE (-6875 6050);
FORCEPROP 1 LAST COMMENT_BODY TRUE
J 2
(-6525 5900);
DISPLAY 0.872340 (-6525 5900);
PAINT GREEN (-6525 5900);
DISPLAY INVISIBLE (-6525 5900);
FORCEPROP 1 LAST OFFPAGE TRUE
J 2
(-6900 5875);
DISPLAY 0.872340 (-6900 5875);
PAINT GREEN (-6900 5875);
DISPLAY INVISIBLE (-6900 5875);
FORCEPROP 2 LAST CDS_LIB standard
J 0
(-6575 6000);
DISPLAY INVISIBLE (-6575 6000);
FORCEADD OFFPAGE..3
R 2
(-6575 4900);
FORCEPROP 2 LAST $XR0 93 
J 0
(-6854 4900);
DISPLAY 0.638298 (-6854 4900);
PAINT MONO (-6854 4900);
FORCEPROP 2 LAST PATH I283
J 0
(-6875 4950);
DISPLAY 1.021277 (-6875 4950);
DISPLAY INVISIBLE (-6875 4950);
FORCEPROP 1 LAST COMMENT_BODY TRUE
J 2
(-6525 4800);
DISPLAY 0.872340 (-6525 4800);
PAINT GREEN (-6525 4800);
DISPLAY INVISIBLE (-6525 4800);
FORCEPROP 1 LAST OFFPAGE TRUE
J 2
(-6900 4775);
DISPLAY 0.872340 (-6900 4775);
PAINT GREEN (-6900 4775);
DISPLAY INVISIBLE (-6900 4775);
FORCEPROP 2 LAST CDS_LIB standard
J 0
(-6575 4900);
DISPLAY INVISIBLE (-6575 4900);
FORCEADD OFFPAGE..3
R 2
(-6575 4950);
FORCEPROP 2 LAST $XR0 93 
J 0
(-6854 4950);
DISPLAY 0.638298 (-6854 4950);
PAINT MONO (-6854 4950);
FORCEPROP 2 LAST PATH I284
J 0
(-6875 5000);
DISPLAY 1.021277 (-6875 5000);
DISPLAY INVISIBLE (-6875 5000);
FORCEPROP 1 LAST COMMENT_BODY TRUE
J 2
(-6525 4850);
DISPLAY 0.872340 (-6525 4850);
PAINT GREEN (-6525 4850);
DISPLAY INVISIBLE (-6525 4850);
FORCEPROP 1 LAST OFFPAGE TRUE
J 2
(-6900 4825);
DISPLAY 0.872340 (-6900 4825);
PAINT GREEN (-6900 4825);
DISPLAY INVISIBLE (-6900 4825);
FORCEPROP 2 LAST CDS_LIB standard
J 0
(-6575 4950);
DISPLAY INVISIBLE (-6575 4950);
FORCEADD TAP..1
R 2
(-5675 4025);
FORCEPROP 3 LASTPIN (-5625 4025) SIG_NAME M_I_CPU0_SB_DQS_DP<9>
J 0
(-5615 4035);
DISPLAY 0.659574 (-5615 4035);
PAINT MONO (-5615 4035);
DISPLAY INVISIBLE (-5615 4035);
FORCEPROP 1 LASTPIN (-5625 4025) BN 9
J 2
(-5613 4033);
DISPLAY 0.489362 (-5613 4033);
PAINT GREEN (-5613 4033);
FORCEPROP 2 LAST CDS_LIB mstr_standard
J 2
(-5675 4025);
DISPLAY 0.723404 (-5675 4025);
PAINT MONO (-5675 4025);
DISPLAY INVISIBLE (-5675 4025);
FORCEPROP 1 LAST BODY_TYPE PLUMBING
J 2
(-5675 4075);
DISPLAY 0.872340 (-5675 4075);
PAINT GREEN (-5675 4075);
DISPLAY INVISIBLE (-5675 4075);
FORCEPROP 1 LAST HDL_TAP TRUE
J 2
(-6000 3900);
DISPLAY 0.872340 (-6000 3900);
DISPLAY INVISIBLE (-6000 3900);
FORCEPROP 1 LAST PATH I285
J 2
(-5673 4025);
DISPLAY 0.872340 (-5673 4025);
PAINT GREEN (-5673 4025);
DISPLAY INVISIBLE (-5673 4025);
FORCEADD TAP..1
R 2
(-5875 4075);
FORCEPROP 3 LASTPIN (-5825 4075) SIG_NAME M_I_CPU0_SB_DQS_DN<8>
J 0
(-5815 4085);
DISPLAY 0.659574 (-5815 4085);
PAINT MONO (-5815 4085);
DISPLAY INVISIBLE (-5815 4085);
FORCEPROP 1 LASTPIN (-5825 4075) BN 8
J 2
(-5813 4083);
DISPLAY 0.489362 (-5813 4083);
PAINT GREEN (-5813 4083);
FORCEPROP 2 LAST CDS_LIB mstr_standard
J 2
(-5875 4075);
DISPLAY 0.723404 (-5875 4075);
PAINT MONO (-5875 4075);
DISPLAY INVISIBLE (-5875 4075);
FORCEPROP 1 LAST BODY_TYPE PLUMBING
J 2
(-5875 4125);
DISPLAY 0.872340 (-5875 4125);
PAINT GREEN (-5875 4125);
DISPLAY INVISIBLE (-5875 4125);
FORCEPROP 1 LAST HDL_TAP TRUE
J 2
(-6200 3950);
DISPLAY 0.872340 (-6200 3950);
DISPLAY INVISIBLE (-6200 3950);
FORCEPROP 1 LAST PATH I286
J 2
(-5873 4075);
DISPLAY 0.872340 (-5873 4075);
PAINT GREEN (-5873 4075);
DISPLAY INVISIBLE (-5873 4075);
FORCEADD TAP..1
R 2
(-5875 3975);
FORCEPROP 3 LASTPIN (-5825 3975) SIG_NAME M_I_CPU0_SB_DQS_DN<9>
J 0
(-5815 3985);
DISPLAY 0.659574 (-5815 3985);
PAINT MONO (-5815 3985);
DISPLAY INVISIBLE (-5815 3985);
FORCEPROP 1 LASTPIN (-5825 3975) BN 9
J 2
(-5813 3983);
DISPLAY 0.489362 (-5813 3983);
PAINT GREEN (-5813 3983);
FORCEPROP 2 LAST CDS_LIB mstr_standard
J 2
(-5875 3975);
DISPLAY 0.723404 (-5875 3975);
PAINT MONO (-5875 3975);
DISPLAY INVISIBLE (-5875 3975);
FORCEPROP 1 LAST BODY_TYPE PLUMBING
J 2
(-5875 4025);
DISPLAY 0.872340 (-5875 4025);
PAINT GREEN (-5875 4025);
DISPLAY INVISIBLE (-5875 4025);
FORCEPROP 1 LAST HDL_TAP TRUE
J 2
(-6200 3850);
DISPLAY 0.872340 (-6200 3850);
DISPLAY INVISIBLE (-6200 3850);
FORCEPROP 1 LAST PATH I287
J 2
(-5873 3975);
DISPLAY 0.872340 (-5873 3975);
PAINT GREEN (-5873 3975);
DISPLAY INVISIBLE (-5873 3975);
FORCEADD TAP..1
R 2
(-5875 3825);
FORCEPROP 3 LASTPIN (-5825 3825) SIG_NAME M_I_CPU0_SA_CA<0>
J 0
(-5815 3835);
DISPLAY 0.659574 (-5815 3835);
PAINT MONO (-5815 3835);
DISPLAY INVISIBLE (-5815 3835);
FORCEPROP 1 LASTPIN (-5825 3825) BN 0
J 2
(-5813 3833);
DISPLAY 0.489362 (-5813 3833);
PAINT GREEN (-5813 3833);
FORCEPROP 2 LAST CDS_LIB mstr_standard
J 0
(-5875 3825);
DISPLAY 0.723404 (-5875 3825);
PAINT MONO (-5875 3825);
DISPLAY INVISIBLE (-5875 3825);
FORCEPROP 1 LAST BODY_TYPE PLUMBING
J 2
(-5875 3875);
DISPLAY 0.872340 (-5875 3875);
PAINT GREEN (-5875 3875);
DISPLAY INVISIBLE (-5875 3875);
FORCEPROP 1 LAST HDL_TAP TRUE
J 2
(-6200 3700);
DISPLAY 0.872340 (-6200 3700);
DISPLAY INVISIBLE (-6200 3700);
FORCEPROP 1 LAST PATH I288
J 2
(-5873 3825);
DISPLAY 0.872340 (-5873 3825);
PAINT GREEN (-5873 3825);
DISPLAY INVISIBLE (-5873 3825);
FORCEADD TAP..1
R 2
(-5875 3775);
FORCEPROP 3 LASTPIN (-5825 3775) SIG_NAME M_I_CPU0_SA_CA<1>
J 0
(-5815 3785);
DISPLAY 0.659574 (-5815 3785);
PAINT MONO (-5815 3785);
DISPLAY INVISIBLE (-5815 3785);
FORCEPROP 1 LASTPIN (-5825 3775) BN 1
J 2
(-5813 3783);
DISPLAY 0.489362 (-5813 3783);
PAINT GREEN (-5813 3783);
FORCEPROP 2 LAST CDS_LIB mstr_standard
J 0
(-5875 3775);
DISPLAY 0.723404 (-5875 3775);
PAINT MONO (-5875 3775);
DISPLAY INVISIBLE (-5875 3775);
FORCEPROP 1 LAST BODY_TYPE PLUMBING
J 2
(-5875 3825);
DISPLAY 0.872340 (-5875 3825);
PAINT GREEN (-5875 3825);
DISPLAY INVISIBLE (-5875 3825);
FORCEPROP 1 LAST HDL_TAP TRUE
J 2
(-6200 3650);
DISPLAY 0.872340 (-6200 3650);
DISPLAY INVISIBLE (-6200 3650);
FORCEPROP 1 LAST PATH I289
J 2
(-5873 3775);
DISPLAY 0.872340 (-5873 3775);
PAINT GREEN (-5873 3775);
DISPLAY INVISIBLE (-5873 3775);
FORCEADD TAP..1
R 2
(-5875 3725);
FORCEPROP 3 LASTPIN (-5825 3725) SIG_NAME M_I_CPU0_SA_CA<2>
J 0
(-5815 3735);
DISPLAY 0.659574 (-5815 3735);
PAINT MONO (-5815 3735);
DISPLAY INVISIBLE (-5815 3735);
FORCEPROP 1 LASTPIN (-5825 3725) BN 2
J 2
(-5813 3733);
DISPLAY 0.489362 (-5813 3733);
PAINT GREEN (-5813 3733);
FORCEPROP 2 LAST CDS_LIB mstr_standard
J 0
(-5875 3725);
DISPLAY 0.723404 (-5875 3725);
PAINT MONO (-5875 3725);
DISPLAY INVISIBLE (-5875 3725);
FORCEPROP 1 LAST BODY_TYPE PLUMBING
J 2
(-5875 3775);
DISPLAY 0.872340 (-5875 3775);
PAINT GREEN (-5875 3775);
DISPLAY INVISIBLE (-5875 3775);
FORCEPROP 1 LAST HDL_TAP TRUE
J 2
(-6200 3600);
DISPLAY 0.872340 (-6200 3600);
DISPLAY INVISIBLE (-6200 3600);
FORCEPROP 1 LAST PATH I290
J 2
(-5873 3725);
DISPLAY 0.872340 (-5873 3725);
PAINT GREEN (-5873 3725);
DISPLAY INVISIBLE (-5873 3725);
FORCEADD TAP..1
R 2
(-5875 3625);
FORCEPROP 3 LASTPIN (-5825 3625) SIG_NAME M_I_CPU0_SA_CA<4>
J 0
(-5815 3635);
DISPLAY 0.659574 (-5815 3635);
PAINT MONO (-5815 3635);
DISPLAY INVISIBLE (-5815 3635);
FORCEPROP 1 LASTPIN (-5825 3625) BN 4
J 2
(-5813 3633);
DISPLAY 0.489362 (-5813 3633);
PAINT GREEN (-5813 3633);
FORCEPROP 2 LAST CDS_LIB mstr_standard
J 0
(-5875 3625);
DISPLAY 0.723404 (-5875 3625);
PAINT MONO (-5875 3625);
DISPLAY INVISIBLE (-5875 3625);
FORCEPROP 1 LAST BODY_TYPE PLUMBING
J 2
(-5875 3675);
DISPLAY 0.872340 (-5875 3675);
PAINT GREEN (-5875 3675);
DISPLAY INVISIBLE (-5875 3675);
FORCEPROP 1 LAST HDL_TAP TRUE
J 2
(-6200 3500);
DISPLAY 0.872340 (-6200 3500);
DISPLAY INVISIBLE (-6200 3500);
FORCEPROP 1 LAST PATH I291
J 2
(-5873 3625);
DISPLAY 0.872340 (-5873 3625);
PAINT GREEN (-5873 3625);
DISPLAY INVISIBLE (-5873 3625);
FORCEADD TAP..1
R 2
(-5875 3675);
FORCEPROP 3 LASTPIN (-5825 3675) SIG_NAME M_I_CPU0_SA_CA<3>
J 0
(-5815 3685);
DISPLAY 0.659574 (-5815 3685);
PAINT MONO (-5815 3685);
DISPLAY INVISIBLE (-5815 3685);
FORCEPROP 1 LASTPIN (-5825 3675) BN 3
J 2
(-5813 3683);
DISPLAY 0.489362 (-5813 3683);
PAINT GREEN (-5813 3683);
FORCEPROP 2 LAST CDS_LIB mstr_standard
J 0
(-5875 3675);
DISPLAY 0.723404 (-5875 3675);
PAINT MONO (-5875 3675);
DISPLAY INVISIBLE (-5875 3675);
FORCEPROP 1 LAST BODY_TYPE PLUMBING
J 2
(-5875 3725);
DISPLAY 0.872340 (-5875 3725);
PAINT GREEN (-5875 3725);
DISPLAY INVISIBLE (-5875 3725);
FORCEPROP 1 LAST HDL_TAP TRUE
J 2
(-6200 3550);
DISPLAY 0.872340 (-6200 3550);
DISPLAY INVISIBLE (-6200 3550);
FORCEPROP 1 LAST PATH I292
J 2
(-5873 3675);
DISPLAY 0.872340 (-5873 3675);
PAINT GREEN (-5873 3675);
DISPLAY INVISIBLE (-5873 3675);
FORCEADD TAP..1
R 2
(-5875 3525);
FORCEPROP 3 LASTPIN (-5825 3525) SIG_NAME M_I_CPU0_SA_CA<6>
J 0
(-5815 3535);
DISPLAY 0.659574 (-5815 3535);
PAINT MONO (-5815 3535);
DISPLAY INVISIBLE (-5815 3535);
FORCEPROP 1 LASTPIN (-5825 3525) BN 6
J 2
(-5813 3533);
DISPLAY 0.489362 (-5813 3533);
PAINT GREEN (-5813 3533);
FORCEPROP 2 LAST CDS_LIB mstr_standard
J 0
(-5875 3525);
DISPLAY 0.723404 (-5875 3525);
PAINT MONO (-5875 3525);
DISPLAY INVISIBLE (-5875 3525);
FORCEPROP 1 LAST BODY_TYPE PLUMBING
J 2
(-5875 3575);
DISPLAY 0.872340 (-5875 3575);
PAINT GREEN (-5875 3575);
DISPLAY INVISIBLE (-5875 3575);
FORCEPROP 1 LAST HDL_TAP TRUE
J 2
(-6200 3400);
DISPLAY 0.872340 (-6200 3400);
DISPLAY INVISIBLE (-6200 3400);
FORCEPROP 1 LAST PATH I293
J 2
(-5873 3525);
DISPLAY 0.872340 (-5873 3525);
PAINT GREEN (-5873 3525);
DISPLAY INVISIBLE (-5873 3525);
FORCEADD TAP..1
R 2
(-5875 3575);
FORCEPROP 3 LASTPIN (-5825 3575) SIG_NAME M_I_CPU0_SA_CA<5>
J 0
(-5815 3585);
DISPLAY 0.659574 (-5815 3585);
PAINT MONO (-5815 3585);
DISPLAY INVISIBLE (-5815 3585);
FORCEPROP 1 LASTPIN (-5825 3575) BN 5
J 2
(-5813 3583);
DISPLAY 0.489362 (-5813 3583);
PAINT GREEN (-5813 3583);
FORCEPROP 2 LAST CDS_LIB mstr_standard
J 0
(-5875 3575);
DISPLAY 0.723404 (-5875 3575);
PAINT MONO (-5875 3575);
DISPLAY INVISIBLE (-5875 3575);
FORCEPROP 1 LAST BODY_TYPE PLUMBING
J 2
(-5875 3625);
DISPLAY 0.872340 (-5875 3625);
PAINT GREEN (-5875 3625);
DISPLAY INVISIBLE (-5875 3625);
FORCEPROP 1 LAST HDL_TAP TRUE
J 2
(-6200 3450);
DISPLAY 0.872340 (-6200 3450);
DISPLAY INVISIBLE (-6200 3450);
FORCEPROP 1 LAST PATH I294
J 2
(-5873 3575);
DISPLAY 0.872340 (-5873 3575);
PAINT GREEN (-5873 3575);
DISPLAY INVISIBLE (-5873 3575);
FORCEADD TAP..1
R 2
(-5875 3375);
FORCEPROP 3 LASTPIN (-5825 3375) SIG_NAME M_I_CPU0_SB_CA<1>
J 0
(-5815 3385);
DISPLAY 0.659574 (-5815 3385);
PAINT MONO (-5815 3385);
DISPLAY INVISIBLE (-5815 3385);
FORCEPROP 1 LASTPIN (-5825 3375) BN 1
J 2
(-5813 3383);
DISPLAY 0.489362 (-5813 3383);
PAINT GREEN (-5813 3383);
FORCEPROP 2 LAST CDS_LIB mstr_standard
J 0
(-5875 3375);
DISPLAY 0.723404 (-5875 3375);
PAINT MONO (-5875 3375);
DISPLAY INVISIBLE (-5875 3375);
FORCEPROP 1 LAST BODY_TYPE PLUMBING
J 2
(-5875 3425);
DISPLAY 0.872340 (-5875 3425);
PAINT GREEN (-5875 3425);
DISPLAY INVISIBLE (-5875 3425);
FORCEPROP 1 LAST HDL_TAP TRUE
J 2
(-6200 3250);
DISPLAY 0.872340 (-6200 3250);
DISPLAY INVISIBLE (-6200 3250);
FORCEPROP 1 LAST PATH I295
J 2
(-5873 3375);
DISPLAY 0.872340 (-5873 3375);
PAINT GREEN (-5873 3375);
DISPLAY INVISIBLE (-5873 3375);
FORCEADD TAP..1
R 2
(-5875 3425);
FORCEPROP 3 LASTPIN (-5825 3425) SIG_NAME M_I_CPU0_SB_CA<0>
J 0
(-5815 3435);
DISPLAY 0.659574 (-5815 3435);
PAINT MONO (-5815 3435);
DISPLAY INVISIBLE (-5815 3435);
FORCEPROP 1 LASTPIN (-5825 3425) BN 0
J 2
(-5813 3433);
DISPLAY 0.489362 (-5813 3433);
PAINT GREEN (-5813 3433);
FORCEPROP 2 LAST CDS_LIB mstr_standard
J 0
(-5875 3425);
DISPLAY 0.723404 (-5875 3425);
PAINT MONO (-5875 3425);
DISPLAY INVISIBLE (-5875 3425);
FORCEPROP 1 LAST BODY_TYPE PLUMBING
J 2
(-5875 3475);
DISPLAY 0.872340 (-5875 3475);
PAINT GREEN (-5875 3475);
DISPLAY INVISIBLE (-5875 3475);
FORCEPROP 1 LAST HDL_TAP TRUE
J 2
(-6200 3300);
DISPLAY 0.872340 (-6200 3300);
DISPLAY INVISIBLE (-6200 3300);
FORCEPROP 1 LAST PATH I296
J 2
(-5873 3425);
DISPLAY 0.872340 (-5873 3425);
PAINT GREEN (-5873 3425);
DISPLAY INVISIBLE (-5873 3425);
FORCEADD TAP..1
R 2
(-5875 3325);
FORCEPROP 3 LASTPIN (-5825 3325) SIG_NAME M_I_CPU0_SB_CA<2>
J 0
(-5815 3335);
DISPLAY 0.659574 (-5815 3335);
PAINT MONO (-5815 3335);
DISPLAY INVISIBLE (-5815 3335);
FORCEPROP 1 LASTPIN (-5825 3325) BN 2
J 2
(-5813 3333);
DISPLAY 0.489362 (-5813 3333);
PAINT GREEN (-5813 3333);
FORCEPROP 2 LAST CDS_LIB mstr_standard
J 0
(-5875 3325);
DISPLAY 0.723404 (-5875 3325);
PAINT MONO (-5875 3325);
DISPLAY INVISIBLE (-5875 3325);
FORCEPROP 1 LAST BODY_TYPE PLUMBING
J 2
(-5875 3375);
DISPLAY 0.872340 (-5875 3375);
PAINT GREEN (-5875 3375);
DISPLAY INVISIBLE (-5875 3375);
FORCEPROP 1 LAST HDL_TAP TRUE
J 2
(-6200 3200);
DISPLAY 0.872340 (-6200 3200);
DISPLAY INVISIBLE (-6200 3200);
FORCEPROP 1 LAST PATH I297
J 2
(-5873 3325);
DISPLAY 0.872340 (-5873 3325);
PAINT GREEN (-5873 3325);
DISPLAY INVISIBLE (-5873 3325);
FORCEADD TAP..1
R 2
(-5875 3275);
FORCEPROP 3 LASTPIN (-5825 3275) SIG_NAME M_I_CPU0_SB_CA<3>
J 0
(-5815 3285);
DISPLAY 0.659574 (-5815 3285);
PAINT MONO (-5815 3285);
DISPLAY INVISIBLE (-5815 3285);
FORCEPROP 1 LASTPIN (-5825 3275) BN 3
J 2
(-5813 3283);
DISPLAY 0.489362 (-5813 3283);
PAINT GREEN (-5813 3283);
FORCEPROP 2 LAST CDS_LIB mstr_standard
J 0
(-5875 3275);
DISPLAY 0.723404 (-5875 3275);
PAINT MONO (-5875 3275);
DISPLAY INVISIBLE (-5875 3275);
FORCEPROP 1 LAST BODY_TYPE PLUMBING
J 2
(-5875 3325);
DISPLAY 0.872340 (-5875 3325);
PAINT GREEN (-5875 3325);
DISPLAY INVISIBLE (-5875 3325);
FORCEPROP 1 LAST HDL_TAP TRUE
J 2
(-6200 3150);
DISPLAY 0.872340 (-6200 3150);
DISPLAY INVISIBLE (-6200 3150);
FORCEPROP 1 LAST PATH I298
J 2
(-5873 3275);
DISPLAY 0.872340 (-5873 3275);
PAINT GREEN (-5873 3275);
DISPLAY INVISIBLE (-5873 3275);
FORCEADD TAP..1
R 2
(-5875 3225);
FORCEPROP 3 LASTPIN (-5825 3225) SIG_NAME M_I_CPU0_SB_CA<4>
J 0
(-5815 3235);
DISPLAY 0.659574 (-5815 3235);
PAINT MONO (-5815 3235);
DISPLAY INVISIBLE (-5815 3235);
FORCEPROP 1 LASTPIN (-5825 3225) BN 4
J 2
(-5813 3233);
DISPLAY 0.489362 (-5813 3233);
PAINT GREEN (-5813 3233);
FORCEPROP 2 LAST CDS_LIB mstr_standard
J 0
(-5875 3225);
DISPLAY 0.723404 (-5875 3225);
PAINT MONO (-5875 3225);
DISPLAY INVISIBLE (-5875 3225);
FORCEPROP 1 LAST BODY_TYPE PLUMBING
J 2
(-5875 3275);
DISPLAY 0.872340 (-5875 3275);
PAINT GREEN (-5875 3275);
DISPLAY INVISIBLE (-5875 3275);
FORCEPROP 1 LAST HDL_TAP TRUE
J 2
(-6200 3100);
DISPLAY 0.872340 (-6200 3100);
DISPLAY INVISIBLE (-6200 3100);
FORCEPROP 1 LAST PATH I299
J 2
(-5873 3225);
DISPLAY 0.872340 (-5873 3225);
PAINT GREEN (-5873 3225);
DISPLAY INVISIBLE (-5873 3225);
FORCEADD TAP..1
R 2
(-5875 3125);
FORCEPROP 3 LASTPIN (-5825 3125) SIG_NAME M_I_CPU0_SB_CA<6>
J 0
(-5815 3135);
DISPLAY 0.659574 (-5815 3135);
PAINT MONO (-5815 3135);
DISPLAY INVISIBLE (-5815 3135);
FORCEPROP 1 LASTPIN (-5825 3125) BN 6
J 2
(-5813 3133);
DISPLAY 0.489362 (-5813 3133);
PAINT GREEN (-5813 3133);
FORCEPROP 2 LAST CDS_LIB mstr_standard
J 0
(-5875 3125);
DISPLAY 0.723404 (-5875 3125);
PAINT MONO (-5875 3125);
DISPLAY INVISIBLE (-5875 3125);
FORCEPROP 1 LAST BODY_TYPE PLUMBING
J 2
(-5875 3175);
DISPLAY 0.872340 (-5875 3175);
PAINT GREEN (-5875 3175);
DISPLAY INVISIBLE (-5875 3175);
FORCEPROP 1 LAST HDL_TAP TRUE
J 2
(-6200 3000);
DISPLAY 0.872340 (-6200 3000);
DISPLAY INVISIBLE (-6200 3000);
FORCEPROP 1 LAST PATH I300
J 2
(-5873 3125);
DISPLAY 0.872340 (-5873 3125);
PAINT GREEN (-5873 3125);
DISPLAY INVISIBLE (-5873 3125);
FORCEADD TAP..1
R 2
(-5875 3175);
FORCEPROP 3 LASTPIN (-5825 3175) SIG_NAME M_I_CPU0_SB_CA<5>
J 0
(-5815 3185);
DISPLAY 0.659574 (-5815 3185);
PAINT MONO (-5815 3185);
DISPLAY INVISIBLE (-5815 3185);
FORCEPROP 1 LASTPIN (-5825 3175) BN 5
J 2
(-5813 3183);
DISPLAY 0.489362 (-5813 3183);
PAINT GREEN (-5813 3183);
FORCEPROP 2 LAST CDS_LIB mstr_standard
J 0
(-5875 3175);
DISPLAY 0.723404 (-5875 3175);
PAINT MONO (-5875 3175);
DISPLAY INVISIBLE (-5875 3175);
FORCEPROP 1 LAST BODY_TYPE PLUMBING
J 2
(-5875 3225);
DISPLAY 0.872340 (-5875 3225);
PAINT GREEN (-5875 3225);
DISPLAY INVISIBLE (-5875 3225);
FORCEPROP 1 LAST HDL_TAP TRUE
J 2
(-6200 3050);
DISPLAY 0.872340 (-6200 3050);
DISPLAY INVISIBLE (-6200 3050);
FORCEPROP 1 LAST PATH I301
J 2
(-5873 3175);
DISPLAY 0.872340 (-5873 3175);
PAINT GREEN (-5873 3175);
DISPLAY INVISIBLE (-5873 3175);
FORCEADD OFFPAGE..2
R 2
(-6475 3850);
FORCEPROP 2 LAST $XR0 93 
J 0
(-6729 3850);
DISPLAY 0.638298 (-6729 3850);
PAINT MONO (-6729 3850);
FORCEPROP 2 LAST PATH I302
J 0
(-6750 3900);
DISPLAY 1.021277 (-6750 3900);
DISPLAY INVISIBLE (-6750 3900);
FORCEPROP 1 LAST COMMENT_BODY TRUE
J 2
(-6430 3755);
DISPLAY 0.872340 (-6430 3755);
PAINT GREEN (-6430 3755);
DISPLAY INVISIBLE (-6430 3755);
FORCEPROP 1 LAST OFFPAGE TRUE
J 2
(-6800 3725);
DISPLAY 0.872340 (-6800 3725);
PAINT GREEN (-6800 3725);
DISPLAY INVISIBLE (-6800 3725);
FORCEPROP 2 LAST CDS_LIB standard
J 0
(-6475 3850);
DISPLAY INVISIBLE (-6475 3850);
FORCEADD OFFPAGE..2
R 2
(-6475 3450);
FORCEPROP 2 LAST $XR0 93 
J 0
(-6729 3450);
DISPLAY 0.638298 (-6729 3450);
PAINT MONO (-6729 3450);
FORCEPROP 2 LAST PATH I303
J 0
(-6750 3500);
DISPLAY 1.021277 (-6750 3500);
DISPLAY INVISIBLE (-6750 3500);
FORCEPROP 1 LAST COMMENT_BODY TRUE
J 2
(-6430 3355);
DISPLAY 0.872340 (-6430 3355);
PAINT GREEN (-6430 3355);
DISPLAY INVISIBLE (-6430 3355);
FORCEPROP 1 LAST OFFPAGE TRUE
J 2
(-6800 3325);
DISPLAY 0.872340 (-6800 3325);
PAINT GREEN (-6800 3325);
DISPLAY INVISIBLE (-6800 3325);
FORCEPROP 2 LAST CDS_LIB standard
J 0
(-6475 3450);
DISPLAY INVISIBLE (-6475 3450);
FORCEADD OFFPAGE..2
R 2
(-6475 2975);
FORCEPROP 2 LAST $XR0 93 
J 0
(-6729 2975);
DISPLAY 0.638298 (-6729 2975);
PAINT MONO (-6729 2975);
FORCEPROP 2 LAST PATH I304
J 0
(-6750 3025);
DISPLAY 1.021277 (-6750 3025);
DISPLAY INVISIBLE (-6750 3025);
FORCEPROP 1 LAST COMMENT_BODY TRUE
J 2
(-6430 2880);
DISPLAY 0.872340 (-6430 2880);
PAINT GREEN (-6430 2880);
DISPLAY INVISIBLE (-6430 2880);
FORCEPROP 1 LAST OFFPAGE TRUE
J 2
(-6800 2850);
DISPLAY 0.872340 (-6800 2850);
PAINT GREEN (-6800 2850);
DISPLAY INVISIBLE (-6800 2850);
FORCEPROP 2 LAST CDS_LIB standard
J 0
(-6475 2975);
DISPLAY INVISIBLE (-6475 2975);
FORCEADD OFFPAGE..2
R 2
(-6475 2925);
FORCEPROP 2 LAST $XR0 93 
J 0
(-6729 2925);
DISPLAY 0.638298 (-6729 2925);
PAINT MONO (-6729 2925);
FORCEPROP 2 LAST PATH I305
J 0
(-6750 2975);
DISPLAY 1.021277 (-6750 2975);
DISPLAY INVISIBLE (-6750 2975);
FORCEPROP 1 LAST COMMENT_BODY TRUE
J 2
(-6430 2830);
DISPLAY 0.872340 (-6430 2830);
PAINT GREEN (-6430 2830);
DISPLAY INVISIBLE (-6430 2830);
FORCEPROP 1 LAST OFFPAGE TRUE
J 2
(-6800 2800);
DISPLAY 0.872340 (-6800 2800);
PAINT GREEN (-6800 2800);
DISPLAY INVISIBLE (-6800 2800);
FORCEPROP 2 LAST CDS_LIB standard
J 0
(-6475 2925);
DISPLAY INVISIBLE (-6475 2925);
FORCEADD OFFPAGE..2
R 2
(-6475 2825);
FORCEPROP 2 LAST $XR0 93 
J 0
(-6729 2825);
DISPLAY 0.638298 (-6729 2825);
PAINT MONO (-6729 2825);
FORCEPROP 2 LAST PATH I306
J 0
(-6750 2875);
DISPLAY 1.021277 (-6750 2875);
DISPLAY INVISIBLE (-6750 2875);
FORCEPROP 1 LAST COMMENT_BODY TRUE
J 2
(-6430 2730);
DISPLAY 0.872340 (-6430 2730);
PAINT GREEN (-6430 2730);
DISPLAY INVISIBLE (-6430 2730);
FORCEPROP 1 LAST OFFPAGE TRUE
J 2
(-6800 2700);
DISPLAY 0.872340 (-6800 2700);
PAINT GREEN (-6800 2700);
DISPLAY INVISIBLE (-6800 2700);
FORCEPROP 2 LAST CDS_LIB standard
J 0
(-6475 2825);
DISPLAY INVISIBLE (-6475 2825);
FORCEADD OFFPAGE..2
R 2
(-6475 2775);
FORCEPROP 2 LAST $XR0 93 
J 0
(-6729 2775);
DISPLAY 0.638298 (-6729 2775);
PAINT MONO (-6729 2775);
FORCEPROP 2 LAST PATH I307
J 0
(-6750 2825);
DISPLAY 1.021277 (-6750 2825);
DISPLAY INVISIBLE (-6750 2825);
FORCEPROP 1 LAST COMMENT_BODY TRUE
J 2
(-6430 2680);
DISPLAY 0.872340 (-6430 2680);
PAINT GREEN (-6430 2680);
DISPLAY INVISIBLE (-6430 2680);
FORCEPROP 1 LAST OFFPAGE TRUE
J 2
(-6800 2650);
DISPLAY 0.872340 (-6800 2650);
PAINT GREEN (-6800 2650);
DISPLAY INVISIBLE (-6800 2650);
FORCEPROP 2 LAST CDS_LIB standard
J 0
(-6475 2775);
DISPLAY INVISIBLE (-6475 2775);
FORCEADD OFFPAGE..1
(-6475 2675);
FORCEPROP 2 LAST $XR0 93 
J 0
(-6726 2675);
DISPLAY 0.638298 (-6726 2675);
PAINT MONO (-6726 2675);
FORCEPROP 2 LAST PATH I308
J 0
(-6725 2725);
DISPLAY 1.021277 (-6725 2725);
DISPLAY INVISIBLE (-6725 2725);
FORCEPROP 1 LAST COMMENT_BODY TRUE
J 0
(-6350 2575);
DISPLAY 0.872340 (-6350 2575);
PAINT GREEN (-6350 2575);
DISPLAY INVISIBLE (-6350 2575);
FORCEPROP 1 LAST OFFPAGE TRUE
J 0
(-6150 2550);
DISPLAY 0.872340 (-6150 2550);
PAINT GREEN (-6150 2550);
DISPLAY INVISIBLE (-6150 2550);
FORCEPROP 2 LAST CDS_LIB standard
J 0
(-6475 2675);
DISPLAY INVISIBLE (-6475 2675);
FORCEADD OFFPAGE..5
(-6475 2575);
FORCEPROP 2 LAST $XR0 93 
J 0
(-6729 2575);
DISPLAY 0.638298 (-6729 2575);
PAINT MONO (-6729 2575);
FORCEPROP 2 LAST PATH I309
J 0
(-6750 2625);
DISPLAY 1.021277 (-6750 2625);
DISPLAY INVISIBLE (-6750 2625);
FORCEPROP 1 LAST COMMENT_BODY TRUE
J 0
(-6375 2500);
DISPLAY 0.872340 (-6375 2500);
PAINT GREEN (-6375 2500);
DISPLAY INVISIBLE (-6375 2500);
FORCEPROP 1 LAST OFFPAGE TRUE
J 0
(-6150 2450);
DISPLAY 0.872340 (-6150 2450);
PAINT GREEN (-6150 2450);
DISPLAY INVISIBLE (-6150 2450);
FORCEPROP 2 LAST CDS_LIB mstr_standard
J 0
(-6475 2575);
DISPLAY INVISIBLE (-6475 2575);
FORCEADD OFFPAGE..2
R 2
(-6475 2475);
FORCEPROP 2 LAST $XR0 93 
J 0
(-6729 2475);
DISPLAY 0.638298 (-6729 2475);
PAINT MONO (-6729 2475);
FORCEPROP 2 LAST PATH I310
J 0
(-6750 2525);
DISPLAY 1.021277 (-6750 2525);
DISPLAY INVISIBLE (-6750 2525);
FORCEPROP 1 LAST COMMENT_BODY TRUE
J 2
(-6430 2380);
DISPLAY 0.872340 (-6430 2380);
PAINT GREEN (-6430 2380);
DISPLAY INVISIBLE (-6430 2380);
FORCEPROP 1 LAST OFFPAGE TRUE
J 2
(-6800 2350);
DISPLAY 0.872340 (-6800 2350);
PAINT GREEN (-6800 2350);
DISPLAY INVISIBLE (-6800 2350);
FORCEPROP 2 LAST CDS_LIB standard
J 0
(-6475 2475);
DISPLAY INVISIBLE (-6475 2475);
FORCEADD OFFPAGE..2
R 2
(-6475 2425);
FORCEPROP 2 LAST $XR0 93 
J 0
(-6729 2425);
DISPLAY 0.638298 (-6729 2425);
PAINT MONO (-6729 2425);
FORCEPROP 2 LAST PATH I311
J 0
(-6750 2475);
DISPLAY 1.021277 (-6750 2475);
DISPLAY INVISIBLE (-6750 2475);
FORCEPROP 1 LAST COMMENT_BODY TRUE
J 2
(-6430 2330);
DISPLAY 0.872340 (-6430 2330);
PAINT GREEN (-6430 2330);
DISPLAY INVISIBLE (-6430 2330);
FORCEPROP 1 LAST OFFPAGE TRUE
J 2
(-6800 2300);
DISPLAY 0.872340 (-6800 2300);
PAINT GREEN (-6800 2300);
DISPLAY INVISIBLE (-6800 2300);
FORCEPROP 2 LAST CDS_LIB standard
J 0
(-6475 2425);
DISPLAY INVISIBLE (-6475 2425);
FORCEADD OFFPAGE..1
(-6475 2325);
FORCEPROP 2 LAST $XR0 93 
J 0
(-6726 2325);
DISPLAY 0.638298 (-6726 2325);
PAINT MONO (-6726 2325);
FORCEPROP 2 LAST PATH I312
J 0
(-6725 2375);
DISPLAY 1.021277 (-6725 2375);
DISPLAY INVISIBLE (-6725 2375);
FORCEPROP 1 LAST COMMENT_BODY TRUE
J 0
(-6350 2225);
DISPLAY 0.872340 (-6350 2225);
PAINT GREEN (-6350 2225);
DISPLAY INVISIBLE (-6350 2225);
FORCEPROP 1 LAST OFFPAGE TRUE
J 0
(-6150 2200);
DISPLAY 0.872340 (-6150 2200);
PAINT GREEN (-6150 2200);
DISPLAY INVISIBLE (-6150 2200);
FORCEPROP 2 LAST CDS_LIB standard
J 0
(-6475 2325);
DISPLAY INVISIBLE (-6475 2325);
FORCEADD OFFPAGE..5
(-6475 2225);
FORCEPROP 2 LAST $XR0 93 
J 0
(-6729 2225);
DISPLAY 0.638298 (-6729 2225);
PAINT MONO (-6729 2225);
FORCEPROP 2 LAST PATH I313
J 0
(-6750 2275);
DISPLAY 1.021277 (-6750 2275);
DISPLAY INVISIBLE (-6750 2275);
FORCEPROP 1 LAST COMMENT_BODY TRUE
J 0
(-6375 2150);
DISPLAY 0.872340 (-6375 2150);
PAINT GREEN (-6375 2150);
DISPLAY INVISIBLE (-6375 2150);
FORCEPROP 1 LAST OFFPAGE TRUE
J 0
(-6150 2100);
DISPLAY 0.872340 (-6150 2100);
PAINT GREEN (-6150 2100);
DISPLAY INVISIBLE (-6150 2100);
FORCEPROP 2 LAST CDS_LIB standard
J 0
(-6475 2225);
DISPLAY INVISIBLE (-6475 2225);
FORCEADD Q_RES..1
(-6800 2125);
FORCEPROP 1 LAST LOCATION R383
J 0
(-7125 2125);
DISPLAY 0.489362 (-7125 2125);
PAINT SKYBLUE (-7125 2125);
FORCEPROP 0 LAST $SEC 1
J 0
(-6975 2175);
DISPLAY 0.680851 (-6975 2175);
PAINT MONO (-6975 2175);
DISPLAY INVISIBLE (-6975 2175);
FORCEPROP 0 LAST CDS_SEC 1
J 0
(-6975 2175);
DISPLAY 1.021277 (-6975 2175);
DISPLAY INVISIBLE (-6975 2175);
FORCEPROP 1 LASTPIN (-6900 2125) $PN 1
J 0
(-6888 2137);
DISPLAY 0.489362 (-6888 2137);
PAINT MONO (-6888 2137);
FORCEPROP 1 LASTPIN (-6700 2125) $PN 2
J 0
(-6738 2137);
DISPLAY 0.489362 (-6738 2137);
PAINT MONO (-6738 2137);
FORCEPROP 1 LAST TOLERANCE 1%
J 0
(-6525 2125);
DISPLAY 0.489362 (-6525 2125);
PAINT SKYBLUE (-6525 2125);
FORCEPROP 1 LAST VALUE 15   
J 2
(-6475 2125);
DISPLAY 0.489362 (-6475 2125);
PAINT SKYBLUE (-6475 2125);
FORCEPROP 1 LAST PART_NUMBER CS01502FB11
J 0
(-6700 2100);
DISPLAY 0.489362 (-6700 2100);
PAINT SKYBLUE (-6700 2100);
FORCEPROP 1 LAST PACK_TYPE 0402LF
J 0
(-7125 2100);
DISPLAY 0.489362 (-7125 2100);
PAINT SKYBLUE (-7125 2100);
FORCEPROP 2 LAST CDS_LIB pure_quanta
J 0
(-6800 2125);
DISPLAY INVISIBLE (-6800 2125);
FORCEPROP 1 LAST PATH I314
J 0
(-6850 2275);
DISPLAY 0.978723 (-6850 2275);
PAINT WHITE (-6850 2275);
DISPLAY INVISIBLE (-6850 2275);
FORCEPROP 1 LAST WATTAGE 1/16W
J 2
(-6575 2250);
DISPLAY 0.638298 (-6575 2250);
PAINT SKYBLUE (-6575 2250);
DISPLAY INVISIBLE (-6575 2250);
FORCEPROP 1 LAST MATERIAL CHIP
J 0
(-6925 2250);
DISPLAY 0.638298 (-6925 2250);
PAINT SKYBLUE (-6925 2250);
DISPLAY INVISIBLE (-6925 2250);
FORCEADD OFFPAGE..1
(-7675 2125);
FORCEPROP 2 LAST $XR0 93 
J 0
(-7926 2125);
DISPLAY 0.638298 (-7926 2125);
PAINT MONO (-7926 2125);
FORCEPROP 2 LAST PATH I315
J 0
(-7950 2175);
DISPLAY 1.021277 (-7950 2175);
DISPLAY INVISIBLE (-7950 2175);
FORCEPROP 1 LAST COMMENT_BODY TRUE
J 0
(-7550 2025);
DISPLAY 0.872340 (-7550 2025);
PAINT GREEN (-7550 2025);
DISPLAY INVISIBLE (-7550 2025);
FORCEPROP 1 LAST OFFPAGE TRUE
J 0
(-7350 2000);
DISPLAY 0.872340 (-7350 2000);
PAINT GREEN (-7350 2000);
DISPLAY INVISIBLE (-7350 2000);
FORCEPROP 2 LAST CDS_LIB mstr_standard
J 0
(-7675 2125);
DISPLAY INVISIBLE (-7675 2125);
FORCEADD OFFPAGE..5
(-6475 2025);
FORCEPROP 2 LAST $XR0 93 
J 0
(-6729 2025);
DISPLAY 0.638298 (-6729 2025);
PAINT MONO (-6729 2025);
FORCEPROP 2 LAST PATH I316
J 0
(-6750 2075);
DISPLAY 1.021277 (-6750 2075);
DISPLAY INVISIBLE (-6750 2075);
FORCEPROP 1 LAST COMMENT_BODY TRUE
J 0
(-6375 1950);
DISPLAY 0.872340 (-6375 1950);
PAINT GREEN (-6375 1950);
DISPLAY INVISIBLE (-6375 1950);
FORCEPROP 1 LAST OFFPAGE TRUE
J 0
(-6150 1900);
DISPLAY 0.872340 (-6150 1900);
PAINT GREEN (-6150 1900);
DISPLAY INVISIBLE (-6150 1900);
FORCEPROP 2 LAST CDS_LIB standard
J 0
(-6475 2025);
DISPLAY INVISIBLE (-6475 2025);
FORCEADD CAD_NOTE..1
(-7600 2425);
FORCEPROP 0 LAST L1 R1948 PLACE CLOSE TO CPU < 25MM
J 0
(-7750 2300);
DISPLAY 0.617021 (-7750 2300);
PAINT WHITE (-7750 2300);
FORCEPROP 2 LAST CDS_LIB pure_quanta_power
J 0
(-7600 2425);
DISPLAY INVISIBLE (-7600 2425);
FORCEPROP 1 LAST COMMENT_BODY TRUE
J 0
(-7575 2525);
DISPLAY 0.574468 (-7575 2525);
PAINT WHITE (-7575 2525);
DISPLAY INVISIBLE (-7575 2525);
FORCEADD QUANTA_TITLE_BLOCK_C..1
(0 0);
FORCEPROP 0 LAST CDS_CON_LAST_MODIFIED Fri Mar 11 14:52:15 2022
J 0
(-1885 15);
DISPLAY INVISIBLE (-1885 15);
FORCEPROP 1 LAST CUSTOM_TXT_CDS <CON_LAST_MODIFIED>
J 0
(-1885 15);
DISPLAY 0.978723 (-1885 15);
FORCEPROP 2 LAST CUSTOM_TXT_CDS <XR_PAGE_TITLE>
J 0
(-7890 5250);
DISPLAY 0.638298 (-7890 5250);
PAINT PINK (-7890 5250);
DISPLAY INVISIBLE (-7890 5250);
FORCEPROP 1 LAST CUSTOM_TXT_CDS <NAME_2>
J 0
(-3175 50);
FORCEPROP 1 LAST CUSTOM_TXT_CDS <NAME_1>
J 0
(-3175 175);
FORCEPROP 1 LAST CUSTOM_TXT_CDS <Q_NUMBER>
J 0
(-1403 103);
DISPLAY 1.212766 (-1403 103);
FORCEPROP 1 LAST CUSTOM_TXT_CDS <Q_PROJ>
J 0
(-2382 102);
DISPLAY 1.212766 (-2382 102);
FORCEPROP 1 LAST CUSTOM_TXT_CDS <Q_REV>
J 0
(-184 103);
DISPLAY 1.212766 (-184 103);
FORCEPROP 1 LAST CUSTOM_TXT_CDS <CON_PAGE_NUM> OF <CON_TOTAL_PAGES>
J 0
(-446 18);
DISPLAY 0.978723 (-446 18);
FORCEPROP 1 LAST Q_TITLE CPU0 DDR CHI
J 0
(-9325 25);
DISPLAY 2.446809 (-9325 25);
PAINT GREEN (-9325 25);
FORCEPROP 1 LAST Q_DEPT BU9
J 1
(-3763 49);
DISPLAY 1.957447 (-3763 49);
PAINT GREEN (-3763 49);
FORCEPROP 2 LAST PAGE_BORDER TRUE
J 0
(-7890 5250);
DISPLAY 0.638298 (-7890 5250);
PAINT PINK (-7890 5250);
DISPLAY INVISIBLE (-7890 5250);
FORCEPROP 2 LAST CDS_LIB pure_quanta
J 0
(0 0);
DISPLAY INVISIBLE (0 0);
FORCEPROP 1 LAST CDS_LMAN_SYM_OUTLINE -9475,6775,100,-125
J 0
(0 0);
DISPLAY 0.468085 (0 0);
PAINT GREEN (0 0);
DISPLAY INVISIBLE (0 0);
FORCEPROP 1 LAST COMMENT_BODY TRUE
J 0
(12 -13);
DISPLAY 0.978723 (12 -13);
PAINT GREEN (12 -13);
DISPLAY INVISIBLE (12 -13);
FORCEPROP 2 LAST CDS_XR_PAGE_TITLE CR-18 : @T6G_MB_LIB.T6G(SCH_1):PAGE18
J 0
(-7890 5250);
DISPLAY 0.638298 (-7890 5250);
PAINT PINK (-7890 5250);
DISPLAY INVISIBLE (-7890 5250);
WIRE 17 -1 (-3200 5750)(-3200 5700);
WIRE 17 -1 (-3200 5800)(-3200 5750);
WIRE 17 -1 (-3200 5700)(-3200 5650);
WIRE 17 -1 (-3200 5650)(-3200 5550);
WIRE 17 -1 (-3200 5850)(-3200 5800);
WIRE 17 -1 (-3200 5900)(-3200 5850);
WIRE 17 -1 (-3200 5550)(-3200 5500);
WIRE 17 -1 (-3200 5500)(-3200 5450);
WIRE 17 -1 (-3200 5950)(-3200 5900);
WIRE 17 -1 (-3200 6000)(-3200 5950);
WIRE 17 -1 (-3200 5450)(-3200 5400);
WIRE 17 -1 (-3200 5400)(-3200 5350);
WIRE 17 -1 (-3200 6000)(-2575 6000);
FORCEPROP 2 LAST SIG_NAME M_I_CPU0_SA_DQ<31:0>
J 2
(-2635 6010);
DISPLAY 0.489362 (-2635 6010);
WIRE 17 -1 (-3200 5350)(-3200 5300);
WIRE 17 -1 (-3200 5300)(-3200 5250);
WIRE 17 -1 (-3200 5250)(-3200 5200);
WIRE 17 -1 (-3200 5100)(-3200 5200);
WIRE 17 -1 (-3200 5050)(-3200 5100);
WIRE 17 -1 (-3200 5000)(-3200 5050);
WIRE 17 -1 (-3200 4950)(-3200 5000);
WIRE 17 -1 (-3200 4950)(-3200 4900);
WIRE 17 -1 (-3200 4900)(-3200 4850);
WIRE 17 -1 (-3200 4850)(-3200 4800);
WIRE 17 -1 (-3200 4800)(-3200 4750);
WIRE 17 -1 (-3200 4750)(-3200 4650);
WIRE 17 -1 (-3200 4650)(-3200 4600);
WIRE 17 -1 (-3200 4600)(-3200 4550);
WIRE 17 -1 (-3200 4550)(-3200 4500);
WIRE 17 -1 (-3200 4450)(-3200 4500);
WIRE 17 -1 (-3200 4400)(-3200 4450);
WIRE 17 -1 (-3200 4350)(-3200 4400);
WIRE 17 -1 (-3200 4300)(-3200 4350);
WIRE 17 -1 (-3200 4200)(-3200 4150);
WIRE 17 -1 (-3200 4200)(-2575 4200);
FORCEPROP 2 LAST SIG_NAME M_I_CPU0_SB_DQ<31:0>
J 2
(-2635 4210);
DISPLAY 0.489362 (-2635 4210);
WIRE 17 -1 (-3200 4150)(-3200 4100);
WIRE 17 -1 (-3200 4100)(-3200 4050);
WIRE 17 -1 (-3200 4050)(-3200 4000);
WIRE 17 -1 (-3200 3550)(-3200 3500);
WIRE 17 -1 (-3200 3600)(-3200 3550);
WIRE 17 -1 (-3200 3500)(-3200 3450);
WIRE 17 -1 (-3200 3450)(-3200 3400);
WIRE 17 -1 (-3200 3650)(-3200 3600);
WIRE 17 -1 (-3200 3700)(-3200 3650);
WIRE 17 -1 (-3200 3300)(-3200 3400);
WIRE 17 -1 (-3200 3250)(-3200 3300);
WIRE 17 -1 (-3200 3750)(-3200 3700);
WIRE 17 -1 (-3200 3850)(-3200 3750);
WIRE 17 -1 (-3200 3200)(-3200 3250);
WIRE 17 -1 (-3200 3150)(-3200 3200);
WIRE 17 -1 (-3200 3900)(-3200 3850);
WIRE 17 -1 (-3200 3950)(-3200 3900);
WIRE 17 -1 (-3200 3150)(-3200 3100);
WIRE 17 -1 (-3200 3100)(-3200 3050);
WIRE 17 -1 (-3200 4000)(-3200 3950);
WIRE 17 -1 (-3200 3050)(-3200 3000);
WIRE 17 -1 (-3200 3000)(-3200 2950);
WIRE 17 -1 (-3200 2950)(-3200 2850);
WIRE 17 -1 (-3200 2850)(-3200 2800);
WIRE 17 -1 (-3200 2800)(-3200 2750);
WIRE 17 -1 (-3200 2750)(-3200 2700);
WIRE 17 -1 (-3200 2650)(-3200 2700);
WIRE 17 -1 (-3200 2600)(-3200 2650);
WIRE 17 -1 (-3200 2550)(-3200 2600);
WIRE 17 -1 (-3200 2500)(-3200 2550);
WIRE 17 -1 (-3200 2400)(-3200 2425);
WIRE 17 -1 (-3200 2400)(-3200 2350);
WIRE 17 -1 (-3200 2425)(-2700 2425);
FORCEPROP 2 LAST SIG_NAME M_I_CPU0_SA_CB<7:0>
J 2
(-2700 2435);
DISPLAY 0.489362 (-2700 2435);
WIRE 17 -1 (-3200 2300)(-3200 2350);
WIRE 17 -1 (-3200 2300)(-3200 2250);
WIRE 17 -1 (-3200 2200)(-3200 2250);
WIRE 17 -1 (-3200 2150)(-3200 2200);
WIRE 17 -1 (-3200 2100)(-3200 2150);
WIRE 17 -1 (-3200 2050)(-3200 2100);
WIRE 17 -1 (-3200 1850)(-3200 1800);
WIRE 17 -1 (-3200 1850)(-3200 1900);
WIRE 17 -1 (-3200 1750)(-3200 1800);
WIRE 17 -1 (-3200 1700)(-3200 1750);
WIRE 17 -1 (-3200 1950)(-3200 1900);
WIRE 17 -1 (-3200 1950)(-3200 1975);
WIRE 17 -1 (-3200 1650)(-3200 1700);
WIRE 17 -1 (-3200 1600)(-3200 1650);
WIRE 17 -1 (-3200 1975)(-2700 1975);
FORCEPROP 2 LAST SIG_NAME M_I_CPU0_SB_CB<7:0>
J 2
(-2700 1985);
DISPLAY 0.489362 (-2700 1985);
WIRE 17 -1 (-5725 5900)(-5725 5800);
WIRE 17 -1 (-5725 6000)(-5725 5900);
WIRE 17 -1 (-5725 5800)(-5725 5700);
WIRE 17 -1 (-5725 5700)(-5725 5600);
WIRE 17 -1 (-5725 6000)(-6525 6000);
FORCEPROP 2 LAST SIG_NAME M_I_CPU0_SA_DQS_DP<9:0>
J 2
(-5960 6010);
DISPLAY 0.489362 (-5960 6010);
WIRE 17 -1 (-5725 5500)(-5725 5600);
WIRE 17 -1 (-5725 5400)(-5725 5500);
WIRE 17 -1 (-5725 5300)(-5725 5400);
WIRE 17 -1 (-5725 5300)(-5725 5200);
WIRE 17 -1 (-5725 5200)(-5725 5100);
WIRE 17 -1 (-5925 5450)(-5925 5550);
WIRE 17 -1 (-5925 5350)(-5925 5450);
WIRE 17 -1 (-5925 5650)(-5925 5550);
WIRE 17 -1 (-5925 5750)(-5925 5650);
WIRE 17 -1 (-5925 5250)(-5925 5350);
WIRE 17 -1 (-5925 5250)(-5925 5150);
WIRE 17 -1 (-5925 5850)(-5925 5750);
WIRE 17 -1 (-5925 5950)(-5925 5850);
FORCEPROP 2 LAST SIG_NAME M_I_CPU0_SA_DQS_DN<9:0>
J 2
(-5960 5960);
DISPLAY 0.489362 (-5960 5960);
WIRE 17 -1 (-5925 5150)(-5925 5050);
WIRE 17 -1 (-5725 4950)(-5725 4850);
WIRE 17 -1 (-5725 4950)(-6525 4950);
FORCEPROP 2 LAST SIG_NAME M_I_CPU0_SB_DQS_DP<9:0>
J 2
(-5960 4960);
DISPLAY 0.489362 (-5960 4960);
WIRE 17 -1 (-5725 4850)(-5725 4750);
WIRE 17 -1 (-5725 4750)(-5725 4650);
WIRE 17 -1 (-5725 4650)(-5725 4550);
WIRE 17 -1 (-5725 4450)(-5725 4550);
WIRE 17 -1 (-5725 4350)(-5725 4450);
WIRE 17 -1 (-5725 4250)(-5725 4350);
WIRE 17 -1 (-5725 4250)(-5725 4150);
WIRE 17 -1 (-5725 4150)(-5725 4050);
WIRE 17 -1 (-5925 4900)(-5925 4800);
FORCEPROP 2 LAST SIG_NAME M_I_CPU0_SB_DQS_DN<9:0>
J 2
(-5960 4910);
DISPLAY 0.489362 (-5960 4910);
WIRE 17 -1 (-5925 4700)(-5925 4600);
WIRE 17 -1 (-5925 4800)(-5925 4700);
WIRE 17 -1 (-5925 4600)(-5925 4500);
WIRE 17 -1 (-5925 4400)(-5925 4500);
WIRE 17 -1 (-5925 4300)(-5925 4400);
WIRE 17 -1 (-5925 4200)(-5925 4300);
WIRE 17 -1 (-5925 4200)(-5925 4100);
WIRE 17 -1 (-5925 4100)(-5925 4000);
WIRE 17 -1 (-5925 3800)(-5925 3850);
WIRE 17 -1 (-5925 3750)(-5925 3800);
WIRE 17 -1 (-5925 3850)(-6425 3850);
FORCEPROP 2 LAST SIG_NAME M_I_CPU0_SA_CA<6:0>
J 0
(-6425 3860);
DISPLAY 0.489362 (-6425 3860);
WIRE 17 -1 (-5925 3400)(-5925 3450);
WIRE 17 -1 (-5925 3350)(-5925 3400);
WIRE 17 -1 (-5925 3450)(-6425 3450);
FORCEPROP 2 LAST SIG_NAME M_I_CPU0_SB_CA<6:0>
J 0
(-6425 3460);
DISPLAY 0.489362 (-6425 3460);
WIRE 17 -1 (-5925 3700)(-5925 3750);
WIRE 17 -1 (-5925 3300)(-5925 3350);
WIRE 17 -1 (-5925 3650)(-5925 3700);
WIRE 17 -1 (-5925 3600)(-5925 3650);
WIRE 17 -1 (-5925 3550)(-5925 3600);
WIRE 17 -1 (-5925 3250)(-5925 3300);
WIRE 17 -1 (-5925 3200)(-5925 3250);
WIRE 17 -1 (-5925 3150)(-5925 3200);
WIRE 17 -1 (-5925 5950)(-6525 5950);
WIRE 17 -1 (-5925 4900)(-6525 4900);
WIRE 16 -1 (-7625 2125)(-6900 2125);
FORCEPROP 2 LAST SIG_NAME M_I_CPU0_ALERT_N
J 0
(-7585 2135);
DISPLAY 0.489362 (-7585 2135);
WIRE 16 -1 (-6425 1175)(-5325 1175);
FORCEPROP 2 LAST SIG_NAME TP_M_I_CPU0_SA_TEST39I
J 0
(-6410 1185);
DISPLAY 0.489362 (-6410 1185);
FORCEPROP 2 LASTPROP $XRERR UNIQUE?
J 0
(-6665 1175);
DISPLAY 0.638298 (-6665 1175);
PAINT MONO (-6665 1175);
DISPLAY INVISIBLE (-6665 1175);
WIRE 16 -1 (-6700 2125)(-5325 2125);
FORCEPROP 2 LAST SIG_NAME M_I_CPU0_ALERT_R_N
J 0
(-6410 2135);
DISPLAY 0.489362 (-6410 2135);
FORCEPROP 2 LASTPROP $XRERR UNIQUE?
J 0
(-6650 2135);
DISPLAY 0.638298 (-6650 2135);
PAINT MONO (-6650 2135);
DISPLAY INVISIBLE (-6650 2135);
WIRE 16 -1 (-6425 2975)(-5325 2975);
FORCEPROP 2 LAST SIG_NAME M_I_CPU0_CLK_DP<0>
J 0
(-6425 2985);
DISPLAY 0.489362 (-6425 2985);
WIRE 16 -1 (-6425 2925)(-5325 2925);
FORCEPROP 2 LAST SIG_NAME M_I_CPU0_CLK_DN<0>
J 0
(-6425 2935);
DISPLAY 0.489362 (-6425 2935);
WIRE 16 -1 (-6425 2825)(-5325 2825);
FORCEPROP 2 LAST SIG_NAME M_I_CPU0_SA_CS_N<0>
J 0
(-6425 2835);
DISPLAY 0.489362 (-6425 2835);
WIRE 16 -1 (-6425 2775)(-5325 2775);
FORCEPROP 2 LAST SIG_NAME M_I_CPU0_SA_CS_N<1>
J 0
(-6425 2785);
DISPLAY 0.489362 (-6425 2785);
WIRE 16 -1 (-6425 2675)(-5325 2675);
FORCEPROP 2 LAST SIG_NAME M_I_CPU0_SA_RSP<0>
J 0
(-6425 2685);
DISPLAY 0.489362 (-6425 2685);
WIRE 16 -1 (-6425 2575)(-5325 2575);
FORCEPROP 2 LAST SIG_NAME M_I_CPU0_SA_PAR
J 0
(-6425 2585);
DISPLAY 0.489362 (-6425 2585);
WIRE 16 -1 (-6425 2475)(-5325 2475);
FORCEPROP 2 LAST SIG_NAME M_I_CPU0_SB_CS_N<0>
J 0
(-6425 2485);
DISPLAY 0.489362 (-6425 2485);
WIRE 16 -1 (-6425 2425)(-5325 2425);
FORCEPROP 2 LAST SIG_NAME M_I_CPU0_SB_CS_N<1>
J 0
(-6425 2435);
DISPLAY 0.489362 (-6425 2435);
WIRE 16 -1 (-6425 2325)(-5325 2325);
FORCEPROP 2 LAST SIG_NAME M_I_CPU0_SB_RSP<0>
J 0
(-6425 2335);
DISPLAY 0.489362 (-6425 2335);
WIRE 16 -1 (-6425 2225)(-5325 2225);
FORCEPROP 2 LAST SIG_NAME M_I_CPU0_SB_PAR
J 0
(-6425 2235);
DISPLAY 0.489362 (-6425 2235);
WIRE 16 -1 (-6425 2025)(-5325 2025);
FORCEPROP 2 LAST SIG_NAME M_I_CPU0_RESET_N
J 0
(-6425 2035);
DISPLAY 0.489362 (-6425 2035);
WIRE 16 -1 (-5825 3975)(-5325 3975);
WIRE 16 -1 (-5825 4075)(-5325 4075);
WIRE 16 -1 (-5825 3125)(-5325 3125);
WIRE 16 -1 (-5825 3525)(-5325 3525);
WIRE 16 -1 (-5825 3175)(-5325 3175);
WIRE 16 -1 (-5825 3575)(-5325 3575);
WIRE 16 -1 (-5825 3225)(-5325 3225);
WIRE 16 -1 (-5825 3625)(-5325 3625);
WIRE 16 -1 (-5825 3275)(-5325 3275);
WIRE 16 -1 (-5825 3675)(-5325 3675);
WIRE 16 -1 (-5825 3325)(-5325 3325);
WIRE 16 -1 (-5825 3725)(-5325 3725);
WIRE 16 -1 (-5825 3375)(-5325 3375);
WIRE 16 -1 (-5825 3775)(-5325 3775);
WIRE 16 -1 (-5825 3425)(-5325 3425);
WIRE 16 -1 (-5825 3825)(-5325 3825);
WIRE 16 -1 (-5625 4025)(-5325 4025);
WIRE 16 -1 (-5825 4175)(-5325 4175);
WIRE 16 -1 (-5825 4275)(-5325 4275);
WIRE 16 -1 (-5825 4375)(-5325 4375);
WIRE 16 -1 (-5825 4475)(-5325 4475);
WIRE 16 -1 (-5825 5025)(-5325 5025);
WIRE 16 -1 (-5825 4575)(-5325 4575);
WIRE 16 -1 (-5825 4675)(-5325 4675);
WIRE 16 -1 (-5825 4775)(-5325 4775);
WIRE 16 -1 (-5825 4875)(-5325 4875);
WIRE 16 -1 (-5625 4125)(-5325 4125);
WIRE 16 -1 (-5625 4225)(-5325 4225);
WIRE 16 -1 (-5625 4325)(-5325 4325);
WIRE 16 -1 (-5625 4425)(-5325 4425);
WIRE 16 -1 (-5625 4525)(-5325 4525);
WIRE 16 -1 (-5625 5075)(-5325 5075);
WIRE 16 -1 (-5625 4625)(-5325 4625);
WIRE 16 -1 (-5625 4725)(-5325 4725);
WIRE 16 -1 (-5625 4825)(-5325 4825);
WIRE 16 -1 (-5625 4925)(-5325 4925);
WIRE 16 -1 (-5825 5525)(-5325 5525);
WIRE 16 -1 (-5825 5625)(-5325 5625);
WIRE 16 -1 (-5825 5725)(-5325 5725);
WIRE 16 -1 (-5825 5825)(-5325 5825);
WIRE 16 -1 (-5825 5925)(-5325 5925);
WIRE 16 -1 (-5825 5125)(-5325 5125);
WIRE 16 -1 (-5825 5225)(-5325 5225);
WIRE 16 -1 (-5825 5325)(-5325 5325);
WIRE 16 -1 (-5825 5425)(-5325 5425);
WIRE 16 -1 (-5625 5175)(-5325 5175);
WIRE 16 -1 (-5625 5275)(-5325 5275);
WIRE 16 -1 (-5625 5375)(-5325 5375);
WIRE 16 -1 (-5625 5475)(-5325 5475);
WIRE 16 -1 (-5625 5575)(-5325 5575);
WIRE 16 -1 (-5625 5975)(-5325 5975);
WIRE 16 -1 (-5625 5675)(-5325 5675);
WIRE 16 -1 (-5625 5775)(-5325 5775);
WIRE 16 -1 (-5625 5875)(-5325 5875);
WIRE 16 -1 (-3725 1825)(-3300 1825);
WIRE 16 -1 (-3725 2025)(-3300 2025);
WIRE 16 -1 (-3725 1875)(-3300 1875);
WIRE 16 -1 (-3725 1925)(-3300 1925);
WIRE 16 -1 (-3725 1575)(-3300 1575);
WIRE 16 -1 (-3725 1625)(-3300 1625);
WIRE 16 -1 (-3725 1675)(-3300 1675);
WIRE 16 -1 (-3725 1725)(-3300 1725);
WIRE 16 -1 (-3725 1775)(-3300 1775);
WIRE 16 -1 (-3725 2975)(-3300 2975);
WIRE 16 -1 (-3725 3025)(-3300 3025);
WIRE 16 -1 (-3725 2075)(-3300 2075);
WIRE 16 -1 (-3725 2475)(-3300 2475);
WIRE 16 -1 (-3725 2125)(-3300 2125);
WIRE 16 -1 (-3725 2525)(-3300 2525);
WIRE 16 -1 (-3725 2175)(-3300 2175);
WIRE 16 -1 (-3725 2225)(-3300 2225);
WIRE 16 -1 (-3725 2275)(-3300 2275);
WIRE 16 -1 (-3725 2325)(-3300 2325);
WIRE 16 -1 (-3725 2375)(-3300 2375);
WIRE 16 -1 (-3725 2575)(-3300 2575);
WIRE 16 -1 (-3725 2625)(-3300 2625);
WIRE 16 -1 (-3725 2675)(-3300 2675);
WIRE 16 -1 (-3725 2725)(-3300 2725);
WIRE 16 -1 (-3725 2775)(-3300 2775);
WIRE 16 -1 (-3725 2825)(-3300 2825);
WIRE 16 -1 (-3725 2925)(-3300 2925);
WIRE 16 -1 (-3725 3925)(-3300 3925);
WIRE 16 -1 (-3725 3575)(-3300 3575);
WIRE 16 -1 (-3725 3975)(-3300 3975);
WIRE 16 -1 (-3725 3625)(-3300 3625);
WIRE 16 -1 (-3725 4025)(-3300 4025);
WIRE 16 -1 (-3725 3075)(-3300 3075);
WIRE 16 -1 (-3725 4075)(-3300 4075);
WIRE 16 -1 (-3725 3125)(-3300 3125);
WIRE 16 -1 (-3725 3175)(-3300 3175);
WIRE 16 -1 (-3725 3225)(-3300 3225);
WIRE 16 -1 (-3725 3275)(-3300 3275);
WIRE 16 -1 (-3725 3675)(-3300 3675);
WIRE 16 -1 (-3725 3375)(-3300 3375);
WIRE 16 -1 (-3725 3725)(-3300 3725);
WIRE 16 -1 (-3725 3425)(-3300 3425);
WIRE 16 -1 (-3725 3825)(-3300 3825);
WIRE 16 -1 (-3725 3475)(-3300 3475);
WIRE 16 -1 (-3725 3875)(-3300 3875);
WIRE 16 -1 (-3725 3525)(-3300 3525);
WIRE 16 -1 (-3725 5025)(-3300 5025);
WIRE 16 -1 (-3725 4425)(-3300 4425);
WIRE 16 -1 (-3725 5075)(-3300 5075);
WIRE 16 -1 (-3725 4475)(-3300 4475);
WIRE 16 -1 (-3725 4525)(-3300 4525);
WIRE 16 -1 (-3725 4575)(-3300 4575);
WIRE 16 -1 (-3725 4625)(-3300 4625);
WIRE 16 -1 (-3725 4125)(-3300 4125);
WIRE 16 -1 (-3725 4725)(-3300 4725);
WIRE 16 -1 (-3725 4175)(-3300 4175);
WIRE 16 -1 (-3725 4775)(-3300 4775);
WIRE 16 -1 (-3725 4825)(-3300 4825);
WIRE 16 -1 (-3725 4875)(-3300 4875);
WIRE 16 -1 (-3725 4275)(-3300 4275);
WIRE 16 -1 (-3725 4325)(-3300 4325);
WIRE 16 -1 (-3725 4925)(-3300 4925);
WIRE 16 -1 (-3725 4975)(-3300 4975);
WIRE 16 -1 (-3725 4375)(-3300 4375);
WIRE 16 -1 (-3725 5725)(-3300 5725);
WIRE 16 -1 (-3725 5775)(-3300 5775);
WIRE 16 -1 (-3725 5825)(-3300 5825);
WIRE 16 -1 (-3725 5175)(-3300 5175);
WIRE 16 -1 (-3725 5875)(-3300 5875);
WIRE 16 -1 (-3725 5225)(-3300 5225);
WIRE 16 -1 (-3725 5925)(-3300 5925);
WIRE 16 -1 (-3725 5275)(-3300 5275);
WIRE 16 -1 (-3725 5975)(-3300 5975);
WIRE 16 -1 (-3725 5325)(-3300 5325);
WIRE 16 -1 (-3725 5375)(-3300 5375);
WIRE 16 -1 (-3725 5425)(-3300 5425);
WIRE 16 -1 (-3725 5475)(-3300 5475);
WIRE 16 -1 (-3725 5525)(-3300 5525);
WIRE 16 -1 (-3725 5625)(-3300 5625);
WIRE 16 -1 (-3725 5675)(-3300 5675);
QUIT
